FILE_TYPE = MACRO_DRAWING;
SET COLOR_WIRE YELLOW;
SET COLOR_PROP ORANGE;
SET COLOR_DOT WHITE;
SET COLOR_ARC YELLOW;
SET COLOR_BODY GREEN;
SET COLOR_NOTE PURPLE;
SET PROP_DISPLAY VALUE;
SET PAGE_NUMBER P54;
FORCEADD OFFPAGE..2
R 2
(-1850 -525);
FORCEPROP 2 LAST $XR1 105 
J 0
(-2225 -525);
DISPLAY 0.638298 (-2225 -525);
PAINT MONO (-2225 -525);
FORCEPROP 2 LAST $XR0 104 
J 0
(-2105 -525);
DISPLAY 0.638298 (-2105 -525);
PAINT MONO (-2105 -525);
FORCEPROP 2 LAST CDS_LIB standard
J 0
(-1850 -525);
PAINT MONO (-1850 -525);
DISPLAY INVISIBLE (-1850 -525);
FORCEPROP 1 LAST OFFPAGE TRUE
J 2
(-2175 -650);
DISPLAY 0.872340 (-2175 -650);
DISPLAY INVISIBLE (-2175 -650);
FORCEPROP 1 LAST COMMENT_BODY TRUE
J 2
(-1805 -620);
DISPLAY 0.872340 (-1805 -620);
PAINT GREEN (-1805 -620);
DISPLAY INVISIBLE (-1805 -620);
FORCEPROP 2 LAST PATH I1
J 0
(-1800 -450);
DISPLAY 1.021277 (-1800 -450);
DISPLAY INVISIBLE (-1800 -450);
FORCEADD OFFPAGE..3
R 2
(-1850 1625);
FORCEPROP 2 LAST $XR1 105 
J 0
(-2280 1625);
DISPLAY 0.638298 (-2280 1625);
PAINT MONO (-2280 1625);
FORCEPROP 2 LAST $XR0 104 
J 0
(-2160 1625);
DISPLAY 0.638298 (-2160 1625);
PAINT MONO (-2160 1625);
FORCEPROP 2 LAST CDS_LIB standard
J 0
(-1850 1625);
DISPLAY INVISIBLE (-1850 1625);
FORCEPROP 1 LAST OFFPAGE TRUE
J 2
(-2175 1500);
DISPLAY 0.872340 (-2175 1500);
DISPLAY INVISIBLE (-2175 1500);
FORCEPROP 1 LAST COMMENT_BODY TRUE
J 2
(-1800 1525);
DISPLAY 0.872340 (-1800 1525);
PAINT GREEN (-1800 1525);
DISPLAY INVISIBLE (-1800 1525);
FORCEPROP 2 LAST PATH I10
J 0
(-1800 1700);
DISPLAY 1.021277 (-1800 1700);
DISPLAY INVISIBLE (-1800 1700);
FORCEADD TAP..1
(2600 0);
FORCEPROP 3 LASTPIN (2550 0) SIG_NAME M_D_CPU1_SB_CS_N<3>
J 0
(2560 10);
DISPLAY 0.659574 (2560 10);
PAINT MONO (2560 10);
DISPLAY INVISIBLE (2560 10);
FORCEPROP 1 LASTPIN (2550 0) BN 3
J 0
(2538 8);
DISPLAY 0.680851 (2538 8);
PAINT GREEN (2538 8);
FORCEPROP 2 LAST CDS_LIB standard
J 0
(2600 0);
DISPLAY INVISIBLE (2600 0);
FORCEPROP 1 LAST BODY_TYPE PLUMBING
J 0
(2600 50);
DISPLAY 0.872340 (2600 50);
PAINT GREEN (2600 50);
DISPLAY INVISIBLE (2600 50);
FORCEPROP 1 LAST HDL_TAP TRUE
J 0
(2925 -125);
DISPLAY 0.872340 (2925 -125);
DISPLAY INVISIBLE (2925 -125);
FORCEPROP 1 LAST PATH I100
J 0
(2598 0);
DISPLAY 0.872340 (2598 0);
PAINT GREEN (2598 0);
DISPLAY INVISIBLE (2598 0);
FORCEADD TAP..1
(2600 150);
FORCEPROP 3 LASTPIN (2550 150) SIG_NAME M_D_CPU1_SA_CS_N<0>
J 0
(2560 160);
DISPLAY 0.659574 (2560 160);
PAINT MONO (2560 160);
DISPLAY INVISIBLE (2560 160);
FORCEPROP 1 LASTPIN (2550 150) BN 0
J 0
(2538 158);
DISPLAY 0.680851 (2538 158);
PAINT GREEN (2538 158);
FORCEPROP 2 LAST CDS_LIB standard
J 0
(2600 150);
DISPLAY INVISIBLE (2600 150);
FORCEPROP 1 LAST BODY_TYPE PLUMBING
J 0
(2600 200);
DISPLAY 0.872340 (2600 200);
PAINT GREEN (2600 200);
DISPLAY INVISIBLE (2600 200);
FORCEPROP 1 LAST HDL_TAP TRUE
J 0
(2925 25);
DISPLAY 0.872340 (2925 25);
DISPLAY INVISIBLE (2925 25);
FORCEPROP 1 LAST PATH I101
J 0
(2598 150);
DISPLAY 0.872340 (2598 150);
PAINT GREEN (2598 150);
DISPLAY INVISIBLE (2598 150);
FORCEADD TAP..1
(2600 200);
FORCEPROP 3 LASTPIN (2550 200) SIG_NAME M_D_CPU1_SA_CS_N<1>
J 0
(2560 210);
DISPLAY 0.659574 (2560 210);
PAINT MONO (2560 210);
DISPLAY INVISIBLE (2560 210);
FORCEPROP 1 LASTPIN (2550 200) BN 1
J 0
(2538 208);
DISPLAY 0.680851 (2538 208);
PAINT GREEN (2538 208);
FORCEPROP 2 LAST CDS_LIB standard
J 0
(2600 200);
DISPLAY INVISIBLE (2600 200);
FORCEPROP 1 LAST BODY_TYPE PLUMBING
J 0
(2600 250);
DISPLAY 0.872340 (2600 250);
PAINT GREEN (2600 250);
DISPLAY INVISIBLE (2600 250);
FORCEPROP 1 LAST HDL_TAP TRUE
J 0
(2925 75);
DISPLAY 0.872340 (2925 75);
DISPLAY INVISIBLE (2925 75);
FORCEPROP 1 LAST PATH I102
J 0
(2598 200);
DISPLAY 0.872340 (2598 200);
PAINT GREEN (2598 200);
DISPLAY INVISIBLE (2598 200);
FORCEADD TAP..1
(2600 300);
FORCEPROP 3 LASTPIN (2550 300) SIG_NAME M_D_CPU1_SA_CS_N<3>
J 0
(2560 310);
DISPLAY 0.659574 (2560 310);
PAINT MONO (2560 310);
DISPLAY INVISIBLE (2560 310);
FORCEPROP 1 LASTPIN (2550 300) BN 3
J 0
(2538 308);
DISPLAY 0.680851 (2538 308);
PAINT GREEN (2538 308);
FORCEPROP 2 LAST CDS_LIB standard
J 0
(2600 300);
DISPLAY INVISIBLE (2600 300);
FORCEPROP 1 LAST BODY_TYPE PLUMBING
J 0
(2600 350);
DISPLAY 0.872340 (2600 350);
PAINT GREEN (2600 350);
DISPLAY INVISIBLE (2600 350);
FORCEPROP 1 LAST HDL_TAP TRUE
J 0
(2925 175);
DISPLAY 0.872340 (2925 175);
DISPLAY INVISIBLE (2925 175);
FORCEPROP 1 LAST PATH I103
J 0
(2598 300);
DISPLAY 0.872340 (2598 300);
PAINT GREEN (2598 300);
DISPLAY INVISIBLE (2598 300);
FORCEADD TAP..1
(2600 250);
FORCEPROP 3 LASTPIN (2550 250) SIG_NAME M_D_CPU1_SA_CS_N<2>
J 0
(2560 260);
DISPLAY 0.659574 (2560 260);
PAINT MONO (2560 260);
DISPLAY INVISIBLE (2560 260);
FORCEPROP 1 LASTPIN (2550 250) BN 2
J 0
(2538 258);
DISPLAY 0.680851 (2538 258);
PAINT GREEN (2538 258);
FORCEPROP 2 LAST CDS_LIB standard
J 0
(2600 250);
DISPLAY INVISIBLE (2600 250);
FORCEPROP 1 LAST BODY_TYPE PLUMBING
J 0
(2600 300);
DISPLAY 0.872340 (2600 300);
PAINT GREEN (2600 300);
DISPLAY INVISIBLE (2600 300);
FORCEPROP 1 LAST HDL_TAP TRUE
J 0
(2925 125);
DISPLAY 0.872340 (2925 125);
DISPLAY INVISIBLE (2925 125);
FORCEPROP 1 LAST PATH I104
J 0
(2598 250);
DISPLAY 0.872340 (2598 250);
PAINT GREEN (2598 250);
DISPLAY INVISIBLE (2598 250);
FORCEADD TAP..1
(2600 500);
FORCEPROP 3 LASTPIN (2550 500) SIG_NAME M_D_CPU1_SB_CA<0>
J 0
(2560 510);
DISPLAY 0.659574 (2560 510);
PAINT MONO (2560 510);
DISPLAY INVISIBLE (2560 510);
FORCEPROP 1 LASTPIN (2550 500) BN 0
J 0
(2538 508);
DISPLAY 0.680851 (2538 508);
PAINT GREEN (2538 508);
FORCEPROP 2 LAST CDS_LIB standard
J 0
(2600 500);
DISPLAY INVISIBLE (2600 500);
FORCEPROP 1 LAST BODY_TYPE PLUMBING
J 0
(2600 550);
DISPLAY 0.872340 (2600 550);
PAINT GREEN (2600 550);
DISPLAY INVISIBLE (2600 550);
FORCEPROP 1 LAST HDL_TAP TRUE
J 0
(2925 375);
DISPLAY 0.872340 (2925 375);
DISPLAY INVISIBLE (2925 375);
FORCEPROP 1 LAST PATH I105
J 0
(2598 500);
DISPLAY 0.872340 (2598 500);
PAINT GREEN (2598 500);
DISPLAY INVISIBLE (2598 500);
FORCEADD TAP..1
(2600 550);
FORCEPROP 3 LASTPIN (2550 550) SIG_NAME M_D_CPU1_SB_CA<1>
J 0
(2560 560);
DISPLAY 0.659574 (2560 560);
PAINT MONO (2560 560);
DISPLAY INVISIBLE (2560 560);
FORCEPROP 1 LASTPIN (2550 550) BN 1
J 0
(2538 558);
DISPLAY 0.680851 (2538 558);
PAINT GREEN (2538 558);
FORCEPROP 2 LAST CDS_LIB standard
J 0
(2600 550);
DISPLAY INVISIBLE (2600 550);
FORCEPROP 1 LAST BODY_TYPE PLUMBING
J 0
(2600 600);
DISPLAY 0.872340 (2600 600);
PAINT GREEN (2600 600);
DISPLAY INVISIBLE (2600 600);
FORCEPROP 1 LAST HDL_TAP TRUE
J 0
(2925 425);
DISPLAY 0.872340 (2925 425);
DISPLAY INVISIBLE (2925 425);
FORCEPROP 1 LAST PATH I106
J 0
(2598 550);
DISPLAY 0.872340 (2598 550);
PAINT GREEN (2598 550);
DISPLAY INVISIBLE (2598 550);
FORCEADD TAP..1
(2600 600);
FORCEPROP 3 LASTPIN (2550 600) SIG_NAME M_D_CPU1_SB_CA<2>
J 0
(2560 610);
DISPLAY 0.659574 (2560 610);
PAINT MONO (2560 610);
DISPLAY INVISIBLE (2560 610);
FORCEPROP 1 LASTPIN (2550 600) BN 2
J 0
(2538 608);
DISPLAY 0.680851 (2538 608);
PAINT GREEN (2538 608);
FORCEPROP 2 LAST CDS_LIB standard
J 0
(2600 600);
DISPLAY INVISIBLE (2600 600);
FORCEPROP 1 LAST BODY_TYPE PLUMBING
J 0
(2600 650);
DISPLAY 0.872340 (2600 650);
PAINT GREEN (2600 650);
DISPLAY INVISIBLE (2600 650);
FORCEPROP 1 LAST HDL_TAP TRUE
J 0
(2925 475);
DISPLAY 0.872340 (2925 475);
DISPLAY INVISIBLE (2925 475);
FORCEPROP 1 LAST PATH I107
J 0
(2598 600);
DISPLAY 0.872340 (2598 600);
PAINT GREEN (2598 600);
DISPLAY INVISIBLE (2598 600);
FORCEADD TAP..1
(2600 700);
FORCEPROP 3 LASTPIN (2550 700) SIG_NAME M_D_CPU1_SB_CA<4>
J 0
(2560 710);
DISPLAY 0.659574 (2560 710);
PAINT MONO (2560 710);
DISPLAY INVISIBLE (2560 710);
FORCEPROP 1 LASTPIN (2550 700) BN 4
J 0
(2538 708);
DISPLAY 0.680851 (2538 708);
PAINT GREEN (2538 708);
FORCEPROP 2 LAST CDS_LIB standard
J 0
(2600 700);
DISPLAY INVISIBLE (2600 700);
FORCEPROP 1 LAST BODY_TYPE PLUMBING
J 0
(2600 750);
DISPLAY 0.872340 (2600 750);
PAINT GREEN (2600 750);
DISPLAY INVISIBLE (2600 750);
FORCEPROP 1 LAST HDL_TAP TRUE
J 0
(2925 575);
DISPLAY 0.872340 (2925 575);
DISPLAY INVISIBLE (2925 575);
FORCEPROP 1 LAST PATH I108
J 0
(2598 700);
DISPLAY 0.872340 (2598 700);
PAINT GREEN (2598 700);
DISPLAY INVISIBLE (2598 700);
FORCEADD TAP..1
(2600 650);
FORCEPROP 3 LASTPIN (2550 650) SIG_NAME M_D_CPU1_SB_CA<3>
J 0
(2560 660);
DISPLAY 0.659574 (2560 660);
PAINT MONO (2560 660);
DISPLAY INVISIBLE (2560 660);
FORCEPROP 1 LASTPIN (2550 650) BN 3
J 0
(2538 658);
DISPLAY 0.680851 (2538 658);
PAINT GREEN (2538 658);
FORCEPROP 2 LAST CDS_LIB standard
J 0
(2600 650);
DISPLAY INVISIBLE (2600 650);
FORCEPROP 1 LAST BODY_TYPE PLUMBING
J 0
(2600 700);
DISPLAY 0.872340 (2600 700);
PAINT GREEN (2600 700);
DISPLAY INVISIBLE (2600 700);
FORCEPROP 1 LAST HDL_TAP TRUE
J 0
(2925 525);
DISPLAY 0.872340 (2925 525);
DISPLAY INVISIBLE (2925 525);
FORCEPROP 1 LAST PATH I109
J 0
(2598 650);
DISPLAY 0.872340 (2598 650);
PAINT GREEN (2598 650);
DISPLAY INVISIBLE (2598 650);
FORCEADD TAP..1
R 2
(-825 -200);
FORCEPROP 3 LASTPIN (-775 -200) SIG_NAME M_D_CPU1_SB_CB<3>
J 0
(-765 -190);
DISPLAY 0.659574 (-765 -190);
PAINT MONO (-765 -190);
DISPLAY INVISIBLE (-765 -190);
FORCEPROP 1 LASTPIN (-775 -200) BN 3
J 2
(-763 -192);
DISPLAY 0.680851 (-763 -192);
PAINT GREEN (-763 -192);
FORCEPROP 2 LAST CDS_LIB standard
J 0
(-825 -200);
DISPLAY INVISIBLE (-825 -200);
FORCEPROP 1 LAST BODY_TYPE PLUMBING
J 2
(-825 -150);
DISPLAY 0.872340 (-825 -150);
PAINT GREEN (-825 -150);
DISPLAY INVISIBLE (-825 -150);
FORCEPROP 1 LAST HDL_TAP TRUE
J 2
(-1150 -325);
DISPLAY 0.872340 (-1150 -325);
DISPLAY INVISIBLE (-1150 -325);
FORCEPROP 1 LAST PATH I11
J 2
(-823 -200);
DISPLAY 0.872340 (-823 -200);
PAINT GREEN (-823 -200);
DISPLAY INVISIBLE (-823 -200);
FORCEADD TAP..1
(2600 750);
FORCEPROP 3 LASTPIN (2550 750) SIG_NAME M_D_CPU1_SB_CA<5>
J 0
(2560 760);
DISPLAY 0.659574 (2560 760);
PAINT MONO (2560 760);
DISPLAY INVISIBLE (2560 760);
FORCEPROP 1 LASTPIN (2550 750) BN 5
J 0
(2538 758);
DISPLAY 0.680851 (2538 758);
PAINT GREEN (2538 758);
FORCEPROP 2 LAST CDS_LIB standard
J 0
(2600 750);
DISPLAY INVISIBLE (2600 750);
FORCEPROP 1 LAST BODY_TYPE PLUMBING
J 0
(2600 800);
DISPLAY 0.872340 (2600 800);
PAINT GREEN (2600 800);
DISPLAY INVISIBLE (2600 800);
FORCEPROP 1 LAST HDL_TAP TRUE
J 0
(2925 625);
DISPLAY 0.872340 (2925 625);
DISPLAY INVISIBLE (2925 625);
FORCEPROP 1 LAST PATH I110
J 0
(2598 750);
DISPLAY 0.872340 (2598 750);
PAINT GREEN (2598 750);
DISPLAY INVISIBLE (2598 750);
FORCEADD TAP..1
(2600 800);
FORCEPROP 3 LASTPIN (2550 800) SIG_NAME M_D_CPU1_SB_CA<6>
J 0
(2560 810);
DISPLAY 0.659574 (2560 810);
PAINT MONO (2560 810);
DISPLAY INVISIBLE (2560 810);
FORCEPROP 1 LASTPIN (2550 800) BN 6
J 0
(2538 808);
DISPLAY 0.680851 (2538 808);
PAINT GREEN (2538 808);
FORCEPROP 2 LAST CDS_LIB standard
J 0
(2600 800);
DISPLAY INVISIBLE (2600 800);
FORCEPROP 1 LAST BODY_TYPE PLUMBING
J 0
(2600 850);
DISPLAY 0.872340 (2600 850);
PAINT GREEN (2600 850);
DISPLAY INVISIBLE (2600 850);
FORCEPROP 1 LAST HDL_TAP TRUE
J 0
(2925 675);
DISPLAY 0.872340 (2925 675);
DISPLAY INVISIBLE (2925 675);
FORCEPROP 1 LAST PATH I111
J 0
(2598 800);
DISPLAY 0.872340 (2598 800);
PAINT GREEN (2598 800);
DISPLAY INVISIBLE (2598 800);
FORCEADD TAP..1
(2600 1100);
FORCEPROP 3 LASTPIN (2550 1100) SIG_NAME M_D_CPU1_SA_CA<2>
J 0
(2560 1110);
DISPLAY 0.659574 (2560 1110);
PAINT MONO (2560 1110);
DISPLAY INVISIBLE (2560 1110);
FORCEPROP 1 LASTPIN (2550 1100) BN 2
J 0
(2538 1108);
DISPLAY 0.680851 (2538 1108);
PAINT GREEN (2538 1108);
FORCEPROP 2 LAST CDS_LIB standard
J 0
(2600 1100);
DISPLAY INVISIBLE (2600 1100);
FORCEPROP 1 LAST BODY_TYPE PLUMBING
J 0
(2600 1150);
DISPLAY 0.872340 (2600 1150);
PAINT GREEN (2600 1150);
DISPLAY INVISIBLE (2600 1150);
FORCEPROP 1 LAST HDL_TAP TRUE
J 0
(2925 975);
DISPLAY 0.872340 (2925 975);
DISPLAY INVISIBLE (2925 975);
FORCEPROP 1 LAST PATH I112
J 0
(2598 1100);
DISPLAY 0.872340 (2598 1100);
PAINT GREEN (2598 1100);
DISPLAY INVISIBLE (2598 1100);
FORCEADD TAP..1
(2600 1050);
FORCEPROP 3 LASTPIN (2550 1050) SIG_NAME M_D_CPU1_SA_CA<1>
J 0
(2560 1060);
DISPLAY 0.659574 (2560 1060);
PAINT MONO (2560 1060);
DISPLAY INVISIBLE (2560 1060);
FORCEPROP 1 LASTPIN (2550 1050) BN 1
J 0
(2538 1058);
DISPLAY 0.680851 (2538 1058);
PAINT GREEN (2538 1058);
FORCEPROP 2 LAST CDS_LIB standard
J 0
(2600 1050);
DISPLAY INVISIBLE (2600 1050);
FORCEPROP 1 LAST BODY_TYPE PLUMBING
J 0
(2600 1100);
DISPLAY 0.872340 (2600 1100);
PAINT GREEN (2600 1100);
DISPLAY INVISIBLE (2600 1100);
FORCEPROP 1 LAST HDL_TAP TRUE
J 0
(2925 925);
DISPLAY 0.872340 (2925 925);
DISPLAY INVISIBLE (2925 925);
FORCEPROP 1 LAST PATH I113
J 0
(2598 1050);
DISPLAY 0.872340 (2598 1050);
PAINT GREEN (2598 1050);
DISPLAY INVISIBLE (2598 1050);
FORCEADD TAP..1
(2600 1000);
FORCEPROP 3 LASTPIN (2550 1000) SIG_NAME M_D_CPU1_SA_CA<0>
J 0
(2560 1010);
DISPLAY 0.659574 (2560 1010);
PAINT MONO (2560 1010);
DISPLAY INVISIBLE (2560 1010);
FORCEPROP 1 LASTPIN (2550 1000) BN 0
J 0
(2538 1008);
DISPLAY 0.680851 (2538 1008);
PAINT GREEN (2538 1008);
FORCEPROP 2 LAST CDS_LIB standard
J 0
(2600 1000);
DISPLAY INVISIBLE (2600 1000);
FORCEPROP 1 LAST BODY_TYPE PLUMBING
J 0
(2600 1050);
DISPLAY 0.872340 (2600 1050);
PAINT GREEN (2600 1050);
DISPLAY INVISIBLE (2600 1050);
FORCEPROP 1 LAST HDL_TAP TRUE
J 0
(2925 875);
DISPLAY 0.872340 (2925 875);
DISPLAY INVISIBLE (2925 875);
FORCEPROP 1 LAST PATH I114
J 0
(2598 1000);
DISPLAY 0.872340 (2598 1000);
PAINT GREEN (2598 1000);
DISPLAY INVISIBLE (2598 1000);
FORCEADD TAP..1
(2600 1150);
FORCEPROP 3 LASTPIN (2550 1150) SIG_NAME M_D_CPU1_SA_CA<3>
J 0
(2560 1160);
DISPLAY 0.659574 (2560 1160);
PAINT MONO (2560 1160);
DISPLAY INVISIBLE (2560 1160);
FORCEPROP 1 LASTPIN (2550 1150) BN 3
J 0
(2538 1158);
DISPLAY 0.680851 (2538 1158);
PAINT GREEN (2538 1158);
FORCEPROP 2 LAST CDS_LIB standard
J 0
(2600 1150);
DISPLAY INVISIBLE (2600 1150);
FORCEPROP 1 LAST BODY_TYPE PLUMBING
J 0
(2600 1200);
DISPLAY 0.872340 (2600 1200);
PAINT GREEN (2600 1200);
DISPLAY INVISIBLE (2600 1200);
FORCEPROP 1 LAST HDL_TAP TRUE
J 0
(2925 1025);
DISPLAY 0.872340 (2925 1025);
DISPLAY INVISIBLE (2925 1025);
FORCEPROP 1 LAST PATH I115
J 0
(2598 1150);
DISPLAY 0.872340 (2598 1150);
PAINT GREEN (2598 1150);
DISPLAY INVISIBLE (2598 1150);
FORCEADD TAP..1
(2600 1200);
FORCEPROP 3 LASTPIN (2550 1200) SIG_NAME M_D_CPU1_SA_CA<4>
J 0
(2560 1210);
DISPLAY 0.659574 (2560 1210);
PAINT MONO (2560 1210);
DISPLAY INVISIBLE (2560 1210);
FORCEPROP 1 LASTPIN (2550 1200) BN 4
J 0
(2538 1208);
DISPLAY 0.680851 (2538 1208);
PAINT GREEN (2538 1208);
FORCEPROP 2 LAST CDS_LIB standard
J 0
(2600 1200);
DISPLAY INVISIBLE (2600 1200);
FORCEPROP 1 LAST BODY_TYPE PLUMBING
J 0
(2600 1250);
DISPLAY 0.872340 (2600 1250);
PAINT GREEN (2600 1250);
DISPLAY INVISIBLE (2600 1250);
FORCEPROP 1 LAST HDL_TAP TRUE
J 0
(2925 1075);
DISPLAY 0.872340 (2925 1075);
DISPLAY INVISIBLE (2925 1075);
FORCEPROP 1 LAST PATH I116
J 0
(2598 1200);
DISPLAY 0.872340 (2598 1200);
PAINT GREEN (2598 1200);
DISPLAY INVISIBLE (2598 1200);
FORCEADD TAP..1
(2600 1250);
FORCEPROP 3 LASTPIN (2550 1250) SIG_NAME M_D_CPU1_SA_CA<5>
J 0
(2560 1260);
DISPLAY 0.659574 (2560 1260);
PAINT MONO (2560 1260);
DISPLAY INVISIBLE (2560 1260);
FORCEPROP 1 LASTPIN (2550 1250) BN 5
J 0
(2538 1258);
DISPLAY 0.680851 (2538 1258);
PAINT GREEN (2538 1258);
FORCEPROP 2 LAST CDS_LIB standard
J 0
(2600 1250);
DISPLAY INVISIBLE (2600 1250);
FORCEPROP 1 LAST BODY_TYPE PLUMBING
J 0
(2600 1300);
DISPLAY 0.872340 (2600 1300);
PAINT GREEN (2600 1300);
DISPLAY INVISIBLE (2600 1300);
FORCEPROP 1 LAST HDL_TAP TRUE
J 0
(2925 1125);
DISPLAY 0.872340 (2925 1125);
DISPLAY INVISIBLE (2925 1125);
FORCEPROP 1 LAST PATH I117
J 0
(2598 1250);
DISPLAY 0.872340 (2598 1250);
PAINT GREEN (2598 1250);
DISPLAY INVISIBLE (2598 1250);
FORCEADD TAP..1
(2600 1300);
FORCEPROP 3 LASTPIN (2550 1300) SIG_NAME M_D_CPU1_SA_CA<6>
J 0
(2560 1310);
DISPLAY 0.659574 (2560 1310);
PAINT MONO (2560 1310);
DISPLAY INVISIBLE (2560 1310);
FORCEPROP 1 LASTPIN (2550 1300) BN 6
J 0
(2538 1308);
DISPLAY 0.680851 (2538 1308);
PAINT GREEN (2538 1308);
FORCEPROP 2 LAST CDS_LIB standard
J 0
(2600 1300);
DISPLAY INVISIBLE (2600 1300);
FORCEPROP 1 LAST BODY_TYPE PLUMBING
J 0
(2600 1350);
DISPLAY 0.872340 (2600 1350);
PAINT GREEN (2600 1350);
DISPLAY INVISIBLE (2600 1350);
FORCEPROP 1 LAST HDL_TAP TRUE
J 0
(2925 1175);
DISPLAY 0.872340 (2925 1175);
DISPLAY INVISIBLE (2925 1175);
FORCEPROP 1 LAST PATH I118
J 0
(2598 1300);
DISPLAY 0.872340 (2598 1300);
PAINT GREEN (2598 1300);
DISPLAY INVISIBLE (2598 1300);
FORCEADD TAP..1
(2600 1450);
FORCEPROP 3 LASTPIN (2550 1450) SIG_NAME M_D_CPU1_SB_DQS_DN<0>
J 0
(2560 1460);
DISPLAY 0.659574 (2560 1460);
PAINT MONO (2560 1460);
DISPLAY INVISIBLE (2560 1460);
FORCEPROP 1 LASTPIN (2550 1450) BN 0
J 0
(2538 1458);
DISPLAY 0.680851 (2538 1458);
PAINT GREEN (2538 1458);
FORCEPROP 2 LAST CDS_LIB standard
J 0
(2600 1450);
DISPLAY INVISIBLE (2600 1450);
FORCEPROP 1 LAST BODY_TYPE PLUMBING
J 0
(2600 1500);
DISPLAY 0.872340 (2600 1500);
PAINT GREEN (2600 1500);
DISPLAY INVISIBLE (2600 1500);
FORCEPROP 1 LAST HDL_TAP TRUE
J 0
(2925 1325);
DISPLAY 0.872340 (2925 1325);
DISPLAY INVISIBLE (2925 1325);
FORCEPROP 1 LAST PATH I119
J 0
(2598 1450);
DISPLAY 0.872340 (2598 1450);
PAINT GREEN (2598 1450);
DISPLAY INVISIBLE (2598 1450);
FORCEADD TAP..1
R 2
(-825 -250);
FORCEPROP 3 LASTPIN (-775 -250) SIG_NAME M_D_CPU1_SB_CB<2>
J 0
(-765 -240);
DISPLAY 0.659574 (-765 -240);
PAINT MONO (-765 -240);
DISPLAY INVISIBLE (-765 -240);
FORCEPROP 1 LASTPIN (-775 -250) BN 2
J 2
(-763 -242);
DISPLAY 0.680851 (-763 -242);
PAINT GREEN (-763 -242);
FORCEPROP 2 LAST CDS_LIB standard
J 0
(-825 -250);
DISPLAY INVISIBLE (-825 -250);
FORCEPROP 1 LAST BODY_TYPE PLUMBING
J 2
(-825 -200);
DISPLAY 0.872340 (-825 -200);
PAINT GREEN (-825 -200);
DISPLAY INVISIBLE (-825 -200);
FORCEPROP 1 LAST HDL_TAP TRUE
J 2
(-1150 -375);
DISPLAY 0.872340 (-1150 -375);
DISPLAY INVISIBLE (-1150 -375);
FORCEPROP 1 LAST PATH I12
J 2
(-823 -250);
DISPLAY 0.872340 (-823 -250);
PAINT GREEN (-823 -250);
DISPLAY INVISIBLE (-823 -250);
FORCEADD TAP..1
(2600 1500);
FORCEPROP 3 LASTPIN (2550 1500) SIG_NAME M_D_CPU1_SB_DQS_DN<1>
J 0
(2560 1510);
DISPLAY 0.659574 (2560 1510);
PAINT MONO (2560 1510);
DISPLAY INVISIBLE (2560 1510);
FORCEPROP 1 LASTPIN (2550 1500) BN 1
J 0
(2538 1508);
DISPLAY 0.680851 (2538 1508);
PAINT GREEN (2538 1508);
FORCEPROP 2 LAST CDS_LIB standard
J 0
(2600 1500);
DISPLAY INVISIBLE (2600 1500);
FORCEPROP 1 LAST BODY_TYPE PLUMBING
J 0
(2600 1550);
DISPLAY 0.872340 (2600 1550);
PAINT GREEN (2600 1550);
DISPLAY INVISIBLE (2600 1550);
FORCEPROP 1 LAST HDL_TAP TRUE
J 0
(2925 1375);
DISPLAY 0.872340 (2925 1375);
DISPLAY INVISIBLE (2925 1375);
FORCEPROP 1 LAST PATH I120
J 0
(2598 1500);
DISPLAY 0.872340 (2598 1500);
PAINT GREEN (2598 1500);
DISPLAY INVISIBLE (2598 1500);
FORCEADD TAP..1
(2600 1600);
FORCEPROP 3 LASTPIN (2550 1600) SIG_NAME M_D_CPU1_SB_DQS_DN<3>
J 0
(2560 1610);
DISPLAY 0.659574 (2560 1610);
PAINT MONO (2560 1610);
DISPLAY INVISIBLE (2560 1610);
FORCEPROP 1 LASTPIN (2550 1600) BN 3
J 0
(2538 1608);
DISPLAY 0.680851 (2538 1608);
PAINT GREEN (2538 1608);
FORCEPROP 2 LAST CDS_LIB standard
J 0
(2600 1600);
DISPLAY INVISIBLE (2600 1600);
FORCEPROP 1 LAST BODY_TYPE PLUMBING
J 0
(2600 1650);
DISPLAY 0.872340 (2600 1650);
PAINT GREEN (2600 1650);
DISPLAY INVISIBLE (2600 1650);
FORCEPROP 1 LAST HDL_TAP TRUE
J 0
(2925 1475);
DISPLAY 0.872340 (2925 1475);
DISPLAY INVISIBLE (2925 1475);
FORCEPROP 1 LAST PATH I121
J 0
(2598 1600);
DISPLAY 0.872340 (2598 1600);
PAINT GREEN (2598 1600);
DISPLAY INVISIBLE (2598 1600);
FORCEADD TAP..1
(2600 1550);
FORCEPROP 3 LASTPIN (2550 1550) SIG_NAME M_D_CPU1_SB_DQS_DN<2>
J 0
(2560 1560);
DISPLAY 0.659574 (2560 1560);
PAINT MONO (2560 1560);
DISPLAY INVISIBLE (2560 1560);
FORCEPROP 1 LASTPIN (2550 1550) BN 2
J 0
(2538 1558);
DISPLAY 0.680851 (2538 1558);
PAINT GREEN (2538 1558);
FORCEPROP 2 LAST CDS_LIB standard
J 0
(2600 1550);
DISPLAY INVISIBLE (2600 1550);
FORCEPROP 1 LAST BODY_TYPE PLUMBING
J 0
(2600 1600);
DISPLAY 0.872340 (2600 1600);
PAINT GREEN (2600 1600);
DISPLAY INVISIBLE (2600 1600);
FORCEPROP 1 LAST HDL_TAP TRUE
J 0
(2925 1425);
DISPLAY 0.872340 (2925 1425);
DISPLAY INVISIBLE (2925 1425);
FORCEPROP 1 LAST PATH I122
J 0
(2598 1550);
DISPLAY 0.872340 (2598 1550);
PAINT GREEN (2598 1550);
DISPLAY INVISIBLE (2598 1550);
FORCEADD TAP..1
(2600 1650);
FORCEPROP 3 LASTPIN (2550 1650) SIG_NAME M_D_CPU1_SB_DQS_DN<4>
J 0
(2560 1660);
DISPLAY 0.659574 (2560 1660);
PAINT MONO (2560 1660);
DISPLAY INVISIBLE (2560 1660);
FORCEPROP 1 LASTPIN (2550 1650) BN 4
J 0
(2538 1658);
DISPLAY 0.680851 (2538 1658);
PAINT GREEN (2538 1658);
FORCEPROP 2 LAST CDS_LIB standard
J 0
(2600 1650);
DISPLAY INVISIBLE (2600 1650);
FORCEPROP 1 LAST BODY_TYPE PLUMBING
J 0
(2600 1700);
DISPLAY 0.872340 (2600 1700);
PAINT GREEN (2600 1700);
DISPLAY INVISIBLE (2600 1700);
FORCEPROP 1 LAST HDL_TAP TRUE
J 0
(2925 1525);
DISPLAY 0.872340 (2925 1525);
DISPLAY INVISIBLE (2925 1525);
FORCEPROP 1 LAST PATH I123
J 0
(2598 1650);
DISPLAY 0.872340 (2598 1650);
PAINT GREEN (2598 1650);
DISPLAY INVISIBLE (2598 1650);
FORCEADD TAP..1
(2600 1700);
FORCEPROP 3 LASTPIN (2550 1700) SIG_NAME M_D_CPU1_SB_DQS_DN<5>
J 0
(2560 1710);
DISPLAY 0.659574 (2560 1710);
PAINT MONO (2560 1710);
DISPLAY INVISIBLE (2560 1710);
FORCEPROP 1 LASTPIN (2550 1700) BN 5
J 0
(2538 1708);
DISPLAY 0.680851 (2538 1708);
PAINT GREEN (2538 1708);
FORCEPROP 2 LAST CDS_LIB standard
J 0
(2600 1700);
DISPLAY INVISIBLE (2600 1700);
FORCEPROP 1 LAST BODY_TYPE PLUMBING
J 0
(2600 1750);
DISPLAY 0.872340 (2600 1750);
PAINT GREEN (2600 1750);
DISPLAY INVISIBLE (2600 1750);
FORCEPROP 1 LAST HDL_TAP TRUE
J 0
(2925 1575);
DISPLAY 0.872340 (2925 1575);
DISPLAY INVISIBLE (2925 1575);
FORCEPROP 1 LAST PATH I124
J 0
(2598 1700);
DISPLAY 0.872340 (2598 1700);
PAINT GREEN (2598 1700);
DISPLAY INVISIBLE (2598 1700);
FORCEADD TAP..1
(2600 1750);
FORCEPROP 3 LASTPIN (2550 1750) SIG_NAME M_D_CPU1_SB_DQS_DN<6>
J 0
(2560 1760);
DISPLAY 0.659574 (2560 1760);
PAINT MONO (2560 1760);
DISPLAY INVISIBLE (2560 1760);
FORCEPROP 1 LASTPIN (2550 1750) BN 6
J 0
(2538 1758);
DISPLAY 0.680851 (2538 1758);
PAINT GREEN (2538 1758);
FORCEPROP 2 LAST CDS_LIB standard
J 0
(2600 1750);
DISPLAY INVISIBLE (2600 1750);
FORCEPROP 1 LAST BODY_TYPE PLUMBING
J 0
(2600 1800);
DISPLAY 0.872340 (2600 1800);
PAINT GREEN (2600 1800);
DISPLAY INVISIBLE (2600 1800);
FORCEPROP 1 LAST HDL_TAP TRUE
J 0
(2925 1625);
DISPLAY 0.872340 (2925 1625);
DISPLAY INVISIBLE (2925 1625);
FORCEPROP 1 LAST PATH I125
J 0
(2598 1750);
DISPLAY 0.872340 (2598 1750);
PAINT GREEN (2598 1750);
DISPLAY INVISIBLE (2598 1750);
FORCEADD TAP..1
(2600 1850);
FORCEPROP 3 LASTPIN (2550 1850) SIG_NAME M_D_CPU1_SB_DQS_DN<8>
J 0
(2560 1860);
DISPLAY 0.659574 (2560 1860);
PAINT MONO (2560 1860);
DISPLAY INVISIBLE (2560 1860);
FORCEPROP 1 LASTPIN (2550 1850) BN 8
J 0
(2538 1858);
DISPLAY 0.680851 (2538 1858);
PAINT GREEN (2538 1858);
FORCEPROP 2 LAST CDS_LIB standard
J 0
(2600 1850);
DISPLAY INVISIBLE (2600 1850);
FORCEPROP 1 LAST BODY_TYPE PLUMBING
J 0
(2600 1900);
DISPLAY 0.872340 (2600 1900);
PAINT GREEN (2600 1900);
DISPLAY INVISIBLE (2600 1900);
FORCEPROP 1 LAST HDL_TAP TRUE
J 0
(2925 1725);
DISPLAY 0.872340 (2925 1725);
DISPLAY INVISIBLE (2925 1725);
FORCEPROP 1 LAST PATH I126
J 0
(2598 1850);
DISPLAY 0.872340 (2598 1850);
PAINT GREEN (2598 1850);
DISPLAY INVISIBLE (2598 1850);
FORCEADD TAP..1
(2600 1800);
FORCEPROP 3 LASTPIN (2550 1800) SIG_NAME M_D_CPU1_SB_DQS_DN<7>
J 0
(2560 1810);
DISPLAY 0.659574 (2560 1810);
PAINT MONO (2560 1810);
DISPLAY INVISIBLE (2560 1810);
FORCEPROP 1 LASTPIN (2550 1800) BN 7
J 0
(2538 1808);
DISPLAY 0.680851 (2538 1808);
PAINT GREEN (2538 1808);
FORCEPROP 2 LAST CDS_LIB standard
J 0
(2600 1800);
DISPLAY INVISIBLE (2600 1800);
FORCEPROP 1 LAST BODY_TYPE PLUMBING
J 0
(2600 1850);
DISPLAY 0.872340 (2600 1850);
PAINT GREEN (2600 1850);
DISPLAY INVISIBLE (2600 1850);
FORCEPROP 1 LAST HDL_TAP TRUE
J 0
(2925 1675);
DISPLAY 0.872340 (2925 1675);
DISPLAY INVISIBLE (2925 1675);
FORCEPROP 1 LAST PATH I127
J 0
(2598 1800);
DISPLAY 0.872340 (2598 1800);
PAINT GREEN (2598 1800);
DISPLAY INVISIBLE (2598 1800);
FORCEADD TAP..1
(2600 1900);
FORCEPROP 3 LASTPIN (2550 1900) SIG_NAME M_D_CPU1_SB_DQS_DN<9>
J 0
(2560 1910);
DISPLAY 0.659574 (2560 1910);
PAINT MONO (2560 1910);
DISPLAY INVISIBLE (2560 1910);
FORCEPROP 1 LASTPIN (2550 1900) BN 9
J 0
(2538 1908);
DISPLAY 0.680851 (2538 1908);
PAINT GREEN (2538 1908);
FORCEPROP 2 LAST CDS_LIB standard
J 0
(2600 1900);
DISPLAY INVISIBLE (2600 1900);
FORCEPROP 1 LAST BODY_TYPE PLUMBING
J 0
(2600 1950);
DISPLAY 0.872340 (2600 1950);
PAINT GREEN (2600 1950);
DISPLAY INVISIBLE (2600 1950);
FORCEPROP 1 LAST HDL_TAP TRUE
J 0
(2925 1775);
DISPLAY 0.872340 (2925 1775);
DISPLAY INVISIBLE (2925 1775);
FORCEPROP 1 LAST PATH I128
J 0
(2598 1900);
DISPLAY 0.872340 (2598 1900);
PAINT GREEN (2598 1900);
DISPLAY INVISIBLE (2598 1900);
FORCEADD TAP..1
(2600 2000);
FORCEPROP 3 LASTPIN (2550 2000) SIG_NAME M_D_CPU1_SB_DQS_DP<0>
J 0
(2560 2010);
DISPLAY 0.659574 (2560 2010);
PAINT MONO (2560 2010);
DISPLAY INVISIBLE (2560 2010);
FORCEPROP 1 LASTPIN (2550 2000) BN 0
J 0
(2538 2008);
DISPLAY 0.680851 (2538 2008);
PAINT GREEN (2538 2008);
FORCEPROP 2 LAST CDS_LIB standard
J 0
(2600 2000);
DISPLAY INVISIBLE (2600 2000);
FORCEPROP 1 LAST BODY_TYPE PLUMBING
J 0
(2600 2050);
DISPLAY 0.872340 (2600 2050);
PAINT GREEN (2600 2050);
DISPLAY INVISIBLE (2600 2050);
FORCEPROP 1 LAST HDL_TAP TRUE
J 0
(2925 1875);
DISPLAY 0.872340 (2925 1875);
DISPLAY INVISIBLE (2925 1875);
FORCEPROP 1 LAST PATH I129
J 0
(2598 2000);
DISPLAY 0.872340 (2598 2000);
PAINT GREEN (2598 2000);
DISPLAY INVISIBLE (2598 2000);
FORCEADD TAP..1
R 2
(-825 -100);
FORCEPROP 3 LASTPIN (-775 -100) SIG_NAME M_D_CPU1_SB_CB<5>
J 0
(-765 -90);
DISPLAY 0.659574 (-765 -90);
PAINT MONO (-765 -90);
DISPLAY INVISIBLE (-765 -90);
FORCEPROP 1 LASTPIN (-775 -100) BN 5
J 2
(-763 -92);
DISPLAY 0.680851 (-763 -92);
PAINT GREEN (-763 -92);
FORCEPROP 2 LAST CDS_LIB standard
J 0
(-825 -100);
DISPLAY INVISIBLE (-825 -100);
FORCEPROP 1 LAST BODY_TYPE PLUMBING
J 2
(-825 -50);
DISPLAY 0.872340 (-825 -50);
PAINT GREEN (-825 -50);
DISPLAY INVISIBLE (-825 -50);
FORCEPROP 1 LAST HDL_TAP TRUE
J 2
(-1150 -225);
DISPLAY 0.872340 (-1150 -225);
DISPLAY INVISIBLE (-1150 -225);
FORCEPROP 1 LAST PATH I13
J 2
(-823 -100);
DISPLAY 0.872340 (-823 -100);
PAINT GREEN (-823 -100);
DISPLAY INVISIBLE (-823 -100);
FORCEADD TAP..1
(2600 2100);
FORCEPROP 3 LASTPIN (2550 2100) SIG_NAME M_D_CPU1_SB_DQS_DP<2>
J 0
(2560 2110);
DISPLAY 0.659574 (2560 2110);
PAINT MONO (2560 2110);
DISPLAY INVISIBLE (2560 2110);
FORCEPROP 1 LASTPIN (2550 2100) BN 2
J 0
(2538 2108);
DISPLAY 0.680851 (2538 2108);
PAINT GREEN (2538 2108);
FORCEPROP 2 LAST CDS_LIB standard
J 0
(2600 2100);
DISPLAY INVISIBLE (2600 2100);
FORCEPROP 1 LAST BODY_TYPE PLUMBING
J 0
(2600 2150);
DISPLAY 0.872340 (2600 2150);
PAINT GREEN (2600 2150);
DISPLAY INVISIBLE (2600 2150);
FORCEPROP 1 LAST HDL_TAP TRUE
J 0
(2925 1975);
DISPLAY 0.872340 (2925 1975);
DISPLAY INVISIBLE (2925 1975);
FORCEPROP 1 LAST PATH I130
J 0
(2598 2100);
DISPLAY 0.872340 (2598 2100);
PAINT GREEN (2598 2100);
DISPLAY INVISIBLE (2598 2100);
FORCEADD TAP..1
(2600 2050);
FORCEPROP 3 LASTPIN (2550 2050) SIG_NAME M_D_CPU1_SB_DQS_DP<1>
J 0
(2560 2060);
DISPLAY 0.659574 (2560 2060);
PAINT MONO (2560 2060);
DISPLAY INVISIBLE (2560 2060);
FORCEPROP 1 LASTPIN (2550 2050) BN 1
J 0
(2538 2058);
DISPLAY 0.680851 (2538 2058);
PAINT GREEN (2538 2058);
FORCEPROP 2 LAST CDS_LIB standard
J 0
(2600 2050);
DISPLAY INVISIBLE (2600 2050);
FORCEPROP 1 LAST BODY_TYPE PLUMBING
J 0
(2600 2100);
DISPLAY 0.872340 (2600 2100);
PAINT GREEN (2600 2100);
DISPLAY INVISIBLE (2600 2100);
FORCEPROP 1 LAST HDL_TAP TRUE
J 0
(2925 1925);
DISPLAY 0.872340 (2925 1925);
DISPLAY INVISIBLE (2925 1925);
FORCEPROP 1 LAST PATH I131
J 0
(2598 2050);
DISPLAY 0.872340 (2598 2050);
PAINT GREEN (2598 2050);
DISPLAY INVISIBLE (2598 2050);
FORCEADD TAP..1
(2600 2150);
FORCEPROP 3 LASTPIN (2550 2150) SIG_NAME M_D_CPU1_SB_DQS_DP<3>
J 0
(2560 2160);
DISPLAY 0.659574 (2560 2160);
PAINT MONO (2560 2160);
DISPLAY INVISIBLE (2560 2160);
FORCEPROP 1 LASTPIN (2550 2150) BN 3
J 0
(2538 2158);
DISPLAY 0.680851 (2538 2158);
PAINT GREEN (2538 2158);
FORCEPROP 2 LAST CDS_LIB standard
J 0
(2600 2150);
DISPLAY INVISIBLE (2600 2150);
FORCEPROP 1 LAST BODY_TYPE PLUMBING
J 0
(2600 2200);
DISPLAY 0.872340 (2600 2200);
PAINT GREEN (2600 2200);
DISPLAY INVISIBLE (2600 2200);
FORCEPROP 1 LAST HDL_TAP TRUE
J 0
(2925 2025);
DISPLAY 0.872340 (2925 2025);
DISPLAY INVISIBLE (2925 2025);
FORCEPROP 1 LAST PATH I132
J 0
(2598 2150);
DISPLAY 0.872340 (2598 2150);
PAINT GREEN (2598 2150);
DISPLAY INVISIBLE (2598 2150);
FORCEADD TAP..1
(2600 2250);
FORCEPROP 3 LASTPIN (2550 2250) SIG_NAME M_D_CPU1_SB_DQS_DP<5>
J 0
(2560 2260);
DISPLAY 0.659574 (2560 2260);
PAINT MONO (2560 2260);
DISPLAY INVISIBLE (2560 2260);
FORCEPROP 1 LASTPIN (2550 2250) BN 5
J 0
(2538 2258);
DISPLAY 0.680851 (2538 2258);
PAINT GREEN (2538 2258);
FORCEPROP 2 LAST CDS_LIB standard
J 0
(2600 2250);
DISPLAY INVISIBLE (2600 2250);
FORCEPROP 1 LAST BODY_TYPE PLUMBING
J 0
(2600 2300);
DISPLAY 0.872340 (2600 2300);
PAINT GREEN (2600 2300);
DISPLAY INVISIBLE (2600 2300);
FORCEPROP 1 LAST HDL_TAP TRUE
J 0
(2925 2125);
DISPLAY 0.872340 (2925 2125);
DISPLAY INVISIBLE (2925 2125);
FORCEPROP 1 LAST PATH I133
J 0
(2598 2250);
DISPLAY 0.872340 (2598 2250);
PAINT GREEN (2598 2250);
DISPLAY INVISIBLE (2598 2250);
FORCEADD TAP..1
(2600 2200);
FORCEPROP 3 LASTPIN (2550 2200) SIG_NAME M_D_CPU1_SB_DQS_DP<4>
J 0
(2560 2210);
DISPLAY 0.659574 (2560 2210);
PAINT MONO (2560 2210);
DISPLAY INVISIBLE (2560 2210);
FORCEPROP 1 LASTPIN (2550 2200) BN 4
J 0
(2538 2208);
DISPLAY 0.680851 (2538 2208);
PAINT GREEN (2538 2208);
FORCEPROP 2 LAST CDS_LIB standard
J 0
(2600 2200);
DISPLAY INVISIBLE (2600 2200);
FORCEPROP 1 LAST BODY_TYPE PLUMBING
J 0
(2600 2250);
DISPLAY 0.872340 (2600 2250);
PAINT GREEN (2600 2250);
DISPLAY INVISIBLE (2600 2250);
FORCEPROP 1 LAST HDL_TAP TRUE
J 0
(2925 2075);
DISPLAY 0.872340 (2925 2075);
DISPLAY INVISIBLE (2925 2075);
FORCEPROP 1 LAST PATH I134
J 0
(2598 2200);
DISPLAY 0.872340 (2598 2200);
PAINT GREEN (2598 2200);
DISPLAY INVISIBLE (2598 2200);
FORCEADD TAP..1
(2600 2350);
FORCEPROP 3 LASTPIN (2550 2350) SIG_NAME M_D_CPU1_SB_DQS_DP<7>
J 0
(2560 2360);
DISPLAY 0.659574 (2560 2360);
PAINT MONO (2560 2360);
DISPLAY INVISIBLE (2560 2360);
FORCEPROP 1 LASTPIN (2550 2350) BN 7
J 0
(2538 2358);
DISPLAY 0.680851 (2538 2358);
PAINT GREEN (2538 2358);
FORCEPROP 2 LAST CDS_LIB standard
J 0
(2600 2350);
DISPLAY INVISIBLE (2600 2350);
FORCEPROP 1 LAST BODY_TYPE PLUMBING
J 0
(2600 2400);
DISPLAY 0.872340 (2600 2400);
PAINT GREEN (2600 2400);
DISPLAY INVISIBLE (2600 2400);
FORCEPROP 1 LAST HDL_TAP TRUE
J 0
(2925 2225);
DISPLAY 0.872340 (2925 2225);
DISPLAY INVISIBLE (2925 2225);
FORCEPROP 1 LAST PATH I135
J 0
(2598 2350);
DISPLAY 0.872340 (2598 2350);
PAINT GREEN (2598 2350);
DISPLAY INVISIBLE (2598 2350);
FORCEADD TAP..1
(2600 2300);
FORCEPROP 3 LASTPIN (2550 2300) SIG_NAME M_D_CPU1_SB_DQS_DP<6>
J 0
(2560 2310);
DISPLAY 0.659574 (2560 2310);
PAINT MONO (2560 2310);
DISPLAY INVISIBLE (2560 2310);
FORCEPROP 1 LASTPIN (2550 2300) BN 6
J 0
(2538 2308);
DISPLAY 0.680851 (2538 2308);
PAINT GREEN (2538 2308);
FORCEPROP 2 LAST CDS_LIB standard
J 0
(2600 2300);
DISPLAY INVISIBLE (2600 2300);
FORCEPROP 1 LAST BODY_TYPE PLUMBING
J 0
(2600 2350);
DISPLAY 0.872340 (2600 2350);
PAINT GREEN (2600 2350);
DISPLAY INVISIBLE (2600 2350);
FORCEPROP 1 LAST HDL_TAP TRUE
J 0
(2925 2175);
DISPLAY 0.872340 (2925 2175);
DISPLAY INVISIBLE (2925 2175);
FORCEPROP 1 LAST PATH I136
J 0
(2598 2300);
DISPLAY 0.872340 (2598 2300);
PAINT GREEN (2598 2300);
DISPLAY INVISIBLE (2598 2300);
FORCEADD TAP..1
(2600 2400);
FORCEPROP 3 LASTPIN (2550 2400) SIG_NAME M_D_CPU1_SB_DQS_DP<8>
J 0
(2560 2410);
DISPLAY 0.659574 (2560 2410);
PAINT MONO (2560 2410);
DISPLAY INVISIBLE (2560 2410);
FORCEPROP 1 LASTPIN (2550 2400) BN 8
J 0
(2538 2408);
DISPLAY 0.680851 (2538 2408);
PAINT GREEN (2538 2408);
FORCEPROP 2 LAST CDS_LIB standard
J 0
(2600 2400);
DISPLAY INVISIBLE (2600 2400);
FORCEPROP 1 LAST BODY_TYPE PLUMBING
J 0
(2600 2450);
DISPLAY 0.872340 (2600 2450);
PAINT GREEN (2600 2450);
DISPLAY INVISIBLE (2600 2450);
FORCEPROP 1 LAST HDL_TAP TRUE
J 0
(2925 2275);
DISPLAY 0.872340 (2925 2275);
DISPLAY INVISIBLE (2925 2275);
FORCEPROP 1 LAST PATH I137
J 0
(2598 2400);
DISPLAY 0.872340 (2598 2400);
PAINT GREEN (2598 2400);
DISPLAY INVISIBLE (2598 2400);
FORCEADD TAP..1
(2600 2450);
FORCEPROP 3 LASTPIN (2550 2450) SIG_NAME M_D_CPU1_SB_DQS_DP<9>
J 0
(2560 2460);
DISPLAY 0.659574 (2560 2460);
PAINT MONO (2560 2460);
DISPLAY INVISIBLE (2560 2460);
FORCEPROP 1 LASTPIN (2550 2450) BN 9
J 0
(2538 2458);
DISPLAY 0.680851 (2538 2458);
PAINT GREEN (2538 2458);
FORCEPROP 2 LAST CDS_LIB standard
J 0
(2600 2450);
DISPLAY INVISIBLE (2600 2450);
FORCEPROP 1 LAST BODY_TYPE PLUMBING
J 0
(2600 2500);
DISPLAY 0.872340 (2600 2500);
PAINT GREEN (2600 2500);
DISPLAY INVISIBLE (2600 2500);
FORCEPROP 1 LAST HDL_TAP TRUE
J 0
(2925 2325);
DISPLAY 0.872340 (2925 2325);
DISPLAY INVISIBLE (2925 2325);
FORCEPROP 1 LAST PATH I138
J 0
(2598 2450);
DISPLAY 0.872340 (2598 2450);
PAINT GREEN (2598 2450);
DISPLAY INVISIBLE (2598 2450);
FORCEADD TAP..1
(2600 2600);
FORCEPROP 3 LASTPIN (2550 2600) SIG_NAME M_D_CPU1_SA_DQS_DN<0>
J 0
(2560 2610);
DISPLAY 0.659574 (2560 2610);
PAINT MONO (2560 2610);
DISPLAY INVISIBLE (2560 2610);
FORCEPROP 1 LASTPIN (2550 2600) BN 0
J 0
(2538 2608);
DISPLAY 0.680851 (2538 2608);
PAINT GREEN (2538 2608);
FORCEPROP 2 LAST CDS_LIB standard
J 0
(2600 2600);
DISPLAY INVISIBLE (2600 2600);
FORCEPROP 1 LAST BODY_TYPE PLUMBING
J 0
(2600 2650);
DISPLAY 0.872340 (2600 2650);
PAINT GREEN (2600 2650);
DISPLAY INVISIBLE (2600 2650);
FORCEPROP 1 LAST HDL_TAP TRUE
J 0
(2925 2475);
DISPLAY 0.872340 (2925 2475);
DISPLAY INVISIBLE (2925 2475);
FORCEPROP 1 LAST PATH I139
J 0
(2598 2600);
DISPLAY 0.872340 (2598 2600);
PAINT GREEN (2598 2600);
DISPLAY INVISIBLE (2598 2600);
FORCEADD TAP..1
R 2
(-825 -150);
FORCEPROP 3 LASTPIN (-775 -150) SIG_NAME M_D_CPU1_SB_CB<4>
J 0
(-765 -140);
DISPLAY 0.659574 (-765 -140);
PAINT MONO (-765 -140);
DISPLAY INVISIBLE (-765 -140);
FORCEPROP 1 LASTPIN (-775 -150) BN 4
J 2
(-763 -142);
DISPLAY 0.680851 (-763 -142);
PAINT GREEN (-763 -142);
FORCEPROP 2 LAST CDS_LIB standard
J 0
(-825 -150);
DISPLAY INVISIBLE (-825 -150);
FORCEPROP 1 LAST BODY_TYPE PLUMBING
J 2
(-825 -100);
DISPLAY 0.872340 (-825 -100);
PAINT GREEN (-825 -100);
DISPLAY INVISIBLE (-825 -100);
FORCEPROP 1 LAST HDL_TAP TRUE
J 2
(-1150 -275);
DISPLAY 0.872340 (-1150 -275);
DISPLAY INVISIBLE (-1150 -275);
FORCEPROP 1 LAST PATH I14
J 2
(-823 -150);
DISPLAY 0.872340 (-823 -150);
PAINT GREEN (-823 -150);
DISPLAY INVISIBLE (-823 -150);
FORCEADD TAP..1
(2600 2650);
FORCEPROP 3 LASTPIN (2550 2650) SIG_NAME M_D_CPU1_SA_DQS_DN<1>
J 0
(2560 2660);
DISPLAY 0.659574 (2560 2660);
PAINT MONO (2560 2660);
DISPLAY INVISIBLE (2560 2660);
FORCEPROP 1 LASTPIN (2550 2650) BN 1
J 0
(2538 2658);
DISPLAY 0.680851 (2538 2658);
PAINT GREEN (2538 2658);
FORCEPROP 2 LAST CDS_LIB standard
J 0
(2600 2650);
DISPLAY INVISIBLE (2600 2650);
FORCEPROP 1 LAST BODY_TYPE PLUMBING
J 0
(2600 2700);
DISPLAY 0.872340 (2600 2700);
PAINT GREEN (2600 2700);
DISPLAY INVISIBLE (2600 2700);
FORCEPROP 1 LAST HDL_TAP TRUE
J 0
(2925 2525);
DISPLAY 0.872340 (2925 2525);
DISPLAY INVISIBLE (2925 2525);
FORCEPROP 1 LAST PATH I140
J 0
(2598 2650);
DISPLAY 0.872340 (2598 2650);
PAINT GREEN (2598 2650);
DISPLAY INVISIBLE (2598 2650);
FORCEADD TAP..1
(2600 2750);
FORCEPROP 3 LASTPIN (2550 2750) SIG_NAME M_D_CPU1_SA_DQS_DN<3>
J 0
(2560 2760);
DISPLAY 0.659574 (2560 2760);
PAINT MONO (2560 2760);
DISPLAY INVISIBLE (2560 2760);
FORCEPROP 1 LASTPIN (2550 2750) BN 3
J 0
(2538 2758);
DISPLAY 0.680851 (2538 2758);
PAINT GREEN (2538 2758);
FORCEPROP 2 LAST CDS_LIB standard
J 0
(2600 2750);
DISPLAY INVISIBLE (2600 2750);
FORCEPROP 1 LAST BODY_TYPE PLUMBING
J 0
(2600 2800);
DISPLAY 0.872340 (2600 2800);
PAINT GREEN (2600 2800);
DISPLAY INVISIBLE (2600 2800);
FORCEPROP 1 LAST HDL_TAP TRUE
J 0
(2925 2625);
DISPLAY 0.872340 (2925 2625);
DISPLAY INVISIBLE (2925 2625);
FORCEPROP 1 LAST PATH I141
J 0
(2598 2750);
DISPLAY 0.872340 (2598 2750);
PAINT GREEN (2598 2750);
DISPLAY INVISIBLE (2598 2750);
FORCEADD TAP..1
(2600 2700);
FORCEPROP 3 LASTPIN (2550 2700) SIG_NAME M_D_CPU1_SA_DQS_DN<2>
J 0
(2560 2710);
DISPLAY 0.659574 (2560 2710);
PAINT MONO (2560 2710);
DISPLAY INVISIBLE (2560 2710);
FORCEPROP 1 LASTPIN (2550 2700) BN 2
J 0
(2538 2708);
DISPLAY 0.680851 (2538 2708);
PAINT GREEN (2538 2708);
FORCEPROP 2 LAST CDS_LIB standard
J 0
(2600 2700);
DISPLAY INVISIBLE (2600 2700);
FORCEPROP 1 LAST BODY_TYPE PLUMBING
J 0
(2600 2750);
DISPLAY 0.872340 (2600 2750);
PAINT GREEN (2600 2750);
DISPLAY INVISIBLE (2600 2750);
FORCEPROP 1 LAST HDL_TAP TRUE
J 0
(2925 2575);
DISPLAY 0.872340 (2925 2575);
DISPLAY INVISIBLE (2925 2575);
FORCEPROP 1 LAST PATH I142
J 0
(2598 2700);
DISPLAY 0.872340 (2598 2700);
PAINT GREEN (2598 2700);
DISPLAY INVISIBLE (2598 2700);
FORCEADD TAP..1
(2600 2850);
FORCEPROP 3 LASTPIN (2550 2850) SIG_NAME M_D_CPU1_SA_DQS_DN<5>
J 0
(2560 2860);
DISPLAY 0.659574 (2560 2860);
PAINT MONO (2560 2860);
DISPLAY INVISIBLE (2560 2860);
FORCEPROP 1 LASTPIN (2550 2850) BN 5
J 0
(2538 2858);
DISPLAY 0.680851 (2538 2858);
PAINT GREEN (2538 2858);
FORCEPROP 2 LAST CDS_LIB standard
J 0
(2600 2850);
DISPLAY INVISIBLE (2600 2850);
FORCEPROP 1 LAST BODY_TYPE PLUMBING
J 0
(2600 2900);
DISPLAY 0.872340 (2600 2900);
PAINT GREEN (2600 2900);
DISPLAY INVISIBLE (2600 2900);
FORCEPROP 1 LAST HDL_TAP TRUE
J 0
(2925 2725);
DISPLAY 0.872340 (2925 2725);
DISPLAY INVISIBLE (2925 2725);
FORCEPROP 1 LAST PATH I143
J 0
(2598 2850);
DISPLAY 0.872340 (2598 2850);
PAINT GREEN (2598 2850);
DISPLAY INVISIBLE (2598 2850);
FORCEADD TAP..1
(2600 2800);
FORCEPROP 3 LASTPIN (2550 2800) SIG_NAME M_D_CPU1_SA_DQS_DN<4>
J 0
(2560 2810);
DISPLAY 0.659574 (2560 2810);
PAINT MONO (2560 2810);
DISPLAY INVISIBLE (2560 2810);
FORCEPROP 1 LASTPIN (2550 2800) BN 4
J 0
(2538 2808);
DISPLAY 0.680851 (2538 2808);
PAINT GREEN (2538 2808);
FORCEPROP 2 LAST CDS_LIB standard
J 0
(2600 2800);
DISPLAY INVISIBLE (2600 2800);
FORCEPROP 1 LAST BODY_TYPE PLUMBING
J 0
(2600 2850);
DISPLAY 0.872340 (2600 2850);
PAINT GREEN (2600 2850);
DISPLAY INVISIBLE (2600 2850);
FORCEPROP 1 LAST HDL_TAP TRUE
J 0
(2925 2675);
DISPLAY 0.872340 (2925 2675);
DISPLAY INVISIBLE (2925 2675);
FORCEPROP 1 LAST PATH I144
J 0
(2598 2800);
DISPLAY 0.872340 (2598 2800);
PAINT GREEN (2598 2800);
DISPLAY INVISIBLE (2598 2800);
FORCEADD TAP..1
(2600 2900);
FORCEPROP 3 LASTPIN (2550 2900) SIG_NAME M_D_CPU1_SA_DQS_DN<6>
J 0
(2560 2910);
DISPLAY 0.659574 (2560 2910);
PAINT MONO (2560 2910);
DISPLAY INVISIBLE (2560 2910);
FORCEPROP 1 LASTPIN (2550 2900) BN 6
J 0
(2538 2908);
DISPLAY 0.680851 (2538 2908);
PAINT GREEN (2538 2908);
FORCEPROP 2 LAST CDS_LIB standard
J 0
(2600 2900);
DISPLAY INVISIBLE (2600 2900);
FORCEPROP 1 LAST BODY_TYPE PLUMBING
J 0
(2600 2950);
DISPLAY 0.872340 (2600 2950);
PAINT GREEN (2600 2950);
DISPLAY INVISIBLE (2600 2950);
FORCEPROP 1 LAST HDL_TAP TRUE
J 0
(2925 2775);
DISPLAY 0.872340 (2925 2775);
DISPLAY INVISIBLE (2925 2775);
FORCEPROP 1 LAST PATH I145
J 0
(2598 2900);
DISPLAY 0.872340 (2598 2900);
PAINT GREEN (2598 2900);
DISPLAY INVISIBLE (2598 2900);
FORCEADD TAP..1
(2600 2950);
FORCEPROP 3 LASTPIN (2550 2950) SIG_NAME M_D_CPU1_SA_DQS_DN<7>
J 0
(2560 2960);
DISPLAY 0.659574 (2560 2960);
PAINT MONO (2560 2960);
DISPLAY INVISIBLE (2560 2960);
FORCEPROP 1 LASTPIN (2550 2950) BN 7
J 0
(2538 2958);
DISPLAY 0.680851 (2538 2958);
PAINT GREEN (2538 2958);
FORCEPROP 2 LAST CDS_LIB standard
J 0
(2600 2950);
DISPLAY INVISIBLE (2600 2950);
FORCEPROP 1 LAST BODY_TYPE PLUMBING
J 0
(2600 3000);
DISPLAY 0.872340 (2600 3000);
PAINT GREEN (2600 3000);
DISPLAY INVISIBLE (2600 3000);
FORCEPROP 1 LAST HDL_TAP TRUE
J 0
(2925 2825);
DISPLAY 0.872340 (2925 2825);
DISPLAY INVISIBLE (2925 2825);
FORCEPROP 1 LAST PATH I146
J 0
(2598 2950);
DISPLAY 0.872340 (2598 2950);
PAINT GREEN (2598 2950);
DISPLAY INVISIBLE (2598 2950);
FORCEADD TAP..1
(2600 3000);
FORCEPROP 3 LASTPIN (2550 3000) SIG_NAME M_D_CPU1_SA_DQS_DN<8>
J 0
(2560 3010);
DISPLAY 0.659574 (2560 3010);
PAINT MONO (2560 3010);
DISPLAY INVISIBLE (2560 3010);
FORCEPROP 1 LASTPIN (2550 3000) BN 8
J 0
(2538 3008);
DISPLAY 0.680851 (2538 3008);
PAINT GREEN (2538 3008);
FORCEPROP 2 LAST CDS_LIB standard
J 0
(2600 3000);
DISPLAY INVISIBLE (2600 3000);
FORCEPROP 1 LAST BODY_TYPE PLUMBING
J 0
(2600 3050);
DISPLAY 0.872340 (2600 3050);
PAINT GREEN (2600 3050);
DISPLAY INVISIBLE (2600 3050);
FORCEPROP 1 LAST HDL_TAP TRUE
J 0
(2925 2875);
DISPLAY 0.872340 (2925 2875);
DISPLAY INVISIBLE (2925 2875);
FORCEPROP 1 LAST PATH I147
J 0
(2598 3000);
DISPLAY 0.872340 (2598 3000);
PAINT GREEN (2598 3000);
DISPLAY INVISIBLE (2598 3000);
FORCEADD TAP..1
(2600 3050);
FORCEPROP 3 LASTPIN (2550 3050) SIG_NAME M_D_CPU1_SA_DQS_DN<9>
J 0
(2560 3060);
DISPLAY 0.659574 (2560 3060);
PAINT MONO (2560 3060);
DISPLAY INVISIBLE (2560 3060);
FORCEPROP 1 LASTPIN (2550 3050) BN 9
J 0
(2538 3058);
DISPLAY 0.680851 (2538 3058);
PAINT GREEN (2538 3058);
FORCEPROP 2 LAST CDS_LIB standard
J 0
(2600 3050);
DISPLAY INVISIBLE (2600 3050);
FORCEPROP 1 LAST BODY_TYPE PLUMBING
J 0
(2600 3100);
DISPLAY 0.872340 (2600 3100);
PAINT GREEN (2600 3100);
DISPLAY INVISIBLE (2600 3100);
FORCEPROP 1 LAST HDL_TAP TRUE
J 0
(2925 2925);
DISPLAY 0.872340 (2925 2925);
DISPLAY INVISIBLE (2925 2925);
FORCEPROP 1 LAST PATH I148
J 0
(2598 3050);
DISPLAY 0.872340 (2598 3050);
PAINT GREEN (2598 3050);
DISPLAY INVISIBLE (2598 3050);
FORCEADD TAP..1
(2600 3150);
FORCEPROP 3 LASTPIN (2550 3150) SIG_NAME M_D_CPU1_SA_DQS_DP<0>
J 0
(2560 3160);
DISPLAY 0.659574 (2560 3160);
PAINT MONO (2560 3160);
DISPLAY INVISIBLE (2560 3160);
FORCEPROP 1 LASTPIN (2550 3150) BN 0
J 0
(2538 3158);
DISPLAY 0.680851 (2538 3158);
PAINT GREEN (2538 3158);
FORCEPROP 2 LAST CDS_LIB standard
J 0
(2600 3150);
DISPLAY INVISIBLE (2600 3150);
FORCEPROP 1 LAST BODY_TYPE PLUMBING
J 0
(2600 3200);
DISPLAY 0.872340 (2600 3200);
PAINT GREEN (2600 3200);
DISPLAY INVISIBLE (2600 3200);
FORCEPROP 1 LAST HDL_TAP TRUE
J 0
(2925 3025);
DISPLAY 0.872340 (2925 3025);
DISPLAY INVISIBLE (2925 3025);
FORCEPROP 1 LAST PATH I149
J 0
(2598 3150);
DISPLAY 0.872340 (2598 3150);
PAINT GREEN (2598 3150);
DISPLAY INVISIBLE (2598 3150);
FORCEADD TAP..1
R 2
(-825 -50);
FORCEPROP 3 LASTPIN (-775 -50) SIG_NAME M_D_CPU1_SB_CB<6>
J 0
(-765 -40);
DISPLAY 0.659574 (-765 -40);
PAINT MONO (-765 -40);
DISPLAY INVISIBLE (-765 -40);
FORCEPROP 1 LASTPIN (-775 -50) BN 6
J 2
(-763 -42);
DISPLAY 0.680851 (-763 -42);
PAINT GREEN (-763 -42);
FORCEPROP 2 LAST CDS_LIB standard
J 0
(-825 -50);
DISPLAY INVISIBLE (-825 -50);
FORCEPROP 1 LAST BODY_TYPE PLUMBING
J 2
(-825 0);
DISPLAY 0.872340 (-825 0);
PAINT GREEN (-825 0);
DISPLAY INVISIBLE (-825 0);
FORCEPROP 1 LAST HDL_TAP TRUE
J 2
(-1150 -175);
DISPLAY 0.872340 (-1150 -175);
DISPLAY INVISIBLE (-1150 -175);
FORCEPROP 1 LAST PATH I15
J 2
(-823 -50);
DISPLAY 0.872340 (-823 -50);
PAINT GREEN (-823 -50);
DISPLAY INVISIBLE (-823 -50);
FORCEADD TAP..1
(2600 3200);
FORCEPROP 3 LASTPIN (2550 3200) SIG_NAME M_D_CPU1_SA_DQS_DP<1>
J 0
(2560 3210);
DISPLAY 0.659574 (2560 3210);
PAINT MONO (2560 3210);
DISPLAY INVISIBLE (2560 3210);
FORCEPROP 1 LASTPIN (2550 3200) BN 1
J 0
(2538 3208);
DISPLAY 0.680851 (2538 3208);
PAINT GREEN (2538 3208);
FORCEPROP 2 LAST CDS_LIB standard
J 0
(2600 3200);
DISPLAY INVISIBLE (2600 3200);
FORCEPROP 1 LAST BODY_TYPE PLUMBING
J 0
(2600 3250);
DISPLAY 0.872340 (2600 3250);
PAINT GREEN (2600 3250);
DISPLAY INVISIBLE (2600 3250);
FORCEPROP 1 LAST HDL_TAP TRUE
J 0
(2925 3075);
DISPLAY 0.872340 (2925 3075);
DISPLAY INVISIBLE (2925 3075);
FORCEPROP 1 LAST PATH I150
J 0
(2598 3200);
DISPLAY 0.872340 (2598 3200);
PAINT GREEN (2598 3200);
DISPLAY INVISIBLE (2598 3200);
FORCEADD TAP..1
(2600 3250);
FORCEPROP 3 LASTPIN (2550 3250) SIG_NAME M_D_CPU1_SA_DQS_DP<2>
J 0
(2560 3260);
DISPLAY 0.659574 (2560 3260);
PAINT MONO (2560 3260);
DISPLAY INVISIBLE (2560 3260);
FORCEPROP 1 LASTPIN (2550 3250) BN 2
J 0
(2538 3258);
DISPLAY 0.680851 (2538 3258);
PAINT GREEN (2538 3258);
FORCEPROP 2 LAST CDS_LIB standard
J 0
(2600 3250);
DISPLAY INVISIBLE (2600 3250);
FORCEPROP 1 LAST BODY_TYPE PLUMBING
J 0
(2600 3300);
DISPLAY 0.872340 (2600 3300);
PAINT GREEN (2600 3300);
DISPLAY INVISIBLE (2600 3300);
FORCEPROP 1 LAST HDL_TAP TRUE
J 0
(2925 3125);
DISPLAY 0.872340 (2925 3125);
DISPLAY INVISIBLE (2925 3125);
FORCEPROP 1 LAST PATH I151
J 0
(2598 3250);
DISPLAY 0.872340 (2598 3250);
PAINT GREEN (2598 3250);
DISPLAY INVISIBLE (2598 3250);
FORCEADD TAP..1
(2600 3300);
FORCEPROP 3 LASTPIN (2550 3300) SIG_NAME M_D_CPU1_SA_DQS_DP<3>
J 0
(2560 3310);
DISPLAY 0.659574 (2560 3310);
PAINT MONO (2560 3310);
DISPLAY INVISIBLE (2560 3310);
FORCEPROP 1 LASTPIN (2550 3300) BN 3
J 0
(2538 3308);
DISPLAY 0.680851 (2538 3308);
PAINT GREEN (2538 3308);
FORCEPROP 2 LAST CDS_LIB standard
J 0
(2600 3300);
DISPLAY INVISIBLE (2600 3300);
FORCEPROP 1 LAST BODY_TYPE PLUMBING
J 0
(2600 3350);
DISPLAY 0.872340 (2600 3350);
PAINT GREEN (2600 3350);
DISPLAY INVISIBLE (2600 3350);
FORCEPROP 1 LAST HDL_TAP TRUE
J 0
(2925 3175);
DISPLAY 0.872340 (2925 3175);
DISPLAY INVISIBLE (2925 3175);
FORCEPROP 1 LAST PATH I152
J 0
(2598 3300);
DISPLAY 0.872340 (2598 3300);
PAINT GREEN (2598 3300);
DISPLAY INVISIBLE (2598 3300);
FORCEADD TAP..1
(2600 3400);
FORCEPROP 3 LASTPIN (2550 3400) SIG_NAME M_D_CPU1_SA_DQS_DP<5>
J 0
(2560 3410);
DISPLAY 0.659574 (2560 3410);
PAINT MONO (2560 3410);
DISPLAY INVISIBLE (2560 3410);
FORCEPROP 1 LASTPIN (2550 3400) BN 5
J 0
(2538 3408);
DISPLAY 0.680851 (2538 3408);
PAINT GREEN (2538 3408);
FORCEPROP 2 LAST CDS_LIB standard
J 0
(2600 3400);
DISPLAY INVISIBLE (2600 3400);
FORCEPROP 1 LAST BODY_TYPE PLUMBING
J 0
(2600 3450);
DISPLAY 0.872340 (2600 3450);
PAINT GREEN (2600 3450);
DISPLAY INVISIBLE (2600 3450);
FORCEPROP 1 LAST HDL_TAP TRUE
J 0
(2925 3275);
DISPLAY 0.872340 (2925 3275);
DISPLAY INVISIBLE (2925 3275);
FORCEPROP 1 LAST PATH I153
J 0
(2598 3400);
DISPLAY 0.872340 (2598 3400);
PAINT GREEN (2598 3400);
DISPLAY INVISIBLE (2598 3400);
FORCEADD TAP..1
(2600 3350);
FORCEPROP 3 LASTPIN (2550 3350) SIG_NAME M_D_CPU1_SA_DQS_DP<4>
J 0
(2560 3360);
DISPLAY 0.659574 (2560 3360);
PAINT MONO (2560 3360);
DISPLAY INVISIBLE (2560 3360);
FORCEPROP 1 LASTPIN (2550 3350) BN 4
J 0
(2538 3358);
DISPLAY 0.680851 (2538 3358);
PAINT GREEN (2538 3358);
FORCEPROP 2 LAST CDS_LIB standard
J 0
(2600 3350);
DISPLAY INVISIBLE (2600 3350);
FORCEPROP 1 LAST BODY_TYPE PLUMBING
J 0
(2600 3400);
DISPLAY 0.872340 (2600 3400);
PAINT GREEN (2600 3400);
DISPLAY INVISIBLE (2600 3400);
FORCEPROP 1 LAST HDL_TAP TRUE
J 0
(2925 3225);
DISPLAY 0.872340 (2925 3225);
DISPLAY INVISIBLE (2925 3225);
FORCEPROP 1 LAST PATH I154
J 0
(2598 3350);
DISPLAY 0.872340 (2598 3350);
PAINT GREEN (2598 3350);
DISPLAY INVISIBLE (2598 3350);
FORCEADD TAP..1
(2600 3450);
FORCEPROP 3 LASTPIN (2550 3450) SIG_NAME M_D_CPU1_SA_DQS_DP<6>
J 0
(2560 3460);
DISPLAY 0.659574 (2560 3460);
PAINT MONO (2560 3460);
DISPLAY INVISIBLE (2560 3460);
FORCEPROP 1 LASTPIN (2550 3450) BN 6
J 0
(2538 3458);
DISPLAY 0.680851 (2538 3458);
PAINT GREEN (2538 3458);
FORCEPROP 2 LAST CDS_LIB standard
J 0
(2600 3450);
DISPLAY INVISIBLE (2600 3450);
FORCEPROP 1 LAST BODY_TYPE PLUMBING
J 0
(2600 3500);
DISPLAY 0.872340 (2600 3500);
PAINT GREEN (2600 3500);
DISPLAY INVISIBLE (2600 3500);
FORCEPROP 1 LAST HDL_TAP TRUE
J 0
(2925 3325);
DISPLAY 0.872340 (2925 3325);
DISPLAY INVISIBLE (2925 3325);
FORCEPROP 1 LAST PATH I155
J 0
(2598 3450);
DISPLAY 0.872340 (2598 3450);
PAINT GREEN (2598 3450);
DISPLAY INVISIBLE (2598 3450);
FORCEADD TAP..1
(2600 3500);
FORCEPROP 3 LASTPIN (2550 3500) SIG_NAME M_D_CPU1_SA_DQS_DP<7>
J 0
(2560 3510);
DISPLAY 0.659574 (2560 3510);
PAINT MONO (2560 3510);
DISPLAY INVISIBLE (2560 3510);
FORCEPROP 1 LASTPIN (2550 3500) BN 7
J 0
(2538 3508);
DISPLAY 0.680851 (2538 3508);
PAINT GREEN (2538 3508);
FORCEPROP 2 LAST CDS_LIB standard
J 0
(2600 3500);
DISPLAY INVISIBLE (2600 3500);
FORCEPROP 1 LAST BODY_TYPE PLUMBING
J 0
(2600 3550);
DISPLAY 0.872340 (2600 3550);
PAINT GREEN (2600 3550);
DISPLAY INVISIBLE (2600 3550);
FORCEPROP 1 LAST HDL_TAP TRUE
J 0
(2925 3375);
DISPLAY 0.872340 (2925 3375);
DISPLAY INVISIBLE (2925 3375);
FORCEPROP 1 LAST PATH I156
J 0
(2598 3500);
DISPLAY 0.872340 (2598 3500);
PAINT GREEN (2598 3500);
DISPLAY INVISIBLE (2598 3500);
FORCEADD TAP..1
(2600 3550);
FORCEPROP 3 LASTPIN (2550 3550) SIG_NAME M_D_CPU1_SA_DQS_DP<8>
J 0
(2560 3560);
DISPLAY 0.659574 (2560 3560);
PAINT MONO (2560 3560);
DISPLAY INVISIBLE (2560 3560);
FORCEPROP 1 LASTPIN (2550 3550) BN 8
J 0
(2538 3558);
DISPLAY 0.680851 (2538 3558);
PAINT GREEN (2538 3558);
FORCEPROP 2 LAST CDS_LIB standard
J 0
(2600 3550);
DISPLAY INVISIBLE (2600 3550);
FORCEPROP 1 LAST BODY_TYPE PLUMBING
J 0
(2600 3600);
DISPLAY 0.872340 (2600 3600);
PAINT GREEN (2600 3600);
DISPLAY INVISIBLE (2600 3600);
FORCEPROP 1 LAST HDL_TAP TRUE
J 0
(2925 3425);
DISPLAY 0.872340 (2925 3425);
DISPLAY INVISIBLE (2925 3425);
FORCEPROP 1 LAST PATH I157
J 0
(2598 3550);
DISPLAY 0.872340 (2598 3550);
PAINT GREEN (2598 3550);
DISPLAY INVISIBLE (2598 3550);
FORCEADD TAP..1
(2600 3600);
FORCEPROP 3 LASTPIN (2550 3600) SIG_NAME M_D_CPU1_SA_DQS_DP<9>
J 0
(2560 3610);
DISPLAY 0.659574 (2560 3610);
PAINT MONO (2560 3610);
DISPLAY INVISIBLE (2560 3610);
FORCEPROP 1 LASTPIN (2550 3600) BN 9
J 0
(2538 3608);
DISPLAY 0.680851 (2538 3608);
PAINT GREEN (2538 3608);
FORCEPROP 2 LAST CDS_LIB standard
J 0
(2600 3600);
DISPLAY INVISIBLE (2600 3600);
FORCEPROP 1 LAST BODY_TYPE PLUMBING
J 0
(2600 3650);
DISPLAY 0.872340 (2600 3650);
PAINT GREEN (2600 3650);
DISPLAY INVISIBLE (2600 3650);
FORCEPROP 1 LAST HDL_TAP TRUE
J 0
(2925 3475);
DISPLAY 0.872340 (2925 3475);
DISPLAY INVISIBLE (2925 3475);
FORCEPROP 1 LAST PATH I158
J 0
(2598 3600);
DISPLAY 0.872340 (2598 3600);
PAINT GREEN (2598 3600);
DISPLAY INVISIBLE (2598 3600);
FORCEADD OFFPAGE..2
(3700 25);
FORCEPROP 2 LAST $XR1 105 
J 0
(4009 25);
DISPLAY 0.638298 (4009 25);
PAINT MONO (4009 25);
FORCEPROP 2 LAST $XR0 104 
J 0
(3889 25);
DISPLAY 0.638298 (3889 25);
PAINT MONO (3889 25);
FORCEPROP 2 LAST CDS_LIB standard
J 0
(3700 25);
PAINT MONO (3700 25);
DISPLAY INVISIBLE (3700 25);
FORCEPROP 1 LAST OFFPAGE TRUE
J 0
(4025 -100);
DISPLAY 1.170213 (4025 -100);
PAINT GREEN (4025 -100);
DISPLAY INVISIBLE (4025 -100);
FORCEPROP 1 LAST COMMENT_BODY TRUE
J 0
(3655 -70);
DISPLAY 1.170213 (3655 -70);
PAINT GREEN (3655 -70);
DISPLAY INVISIBLE (3655 -70);
FORCEPROP 2 LAST PATH I159
J 0
(3875 100);
DISPLAY 1.021277 (3875 100);
DISPLAY INVISIBLE (3875 100);
FORCEADD TAP..1
R 2
(-825 0);
FORCEPROP 3 LASTPIN (-775 0) SIG_NAME M_D_CPU1_SB_CB<7>
J 0
(-765 10);
DISPLAY 0.659574 (-765 10);
PAINT MONO (-765 10);
DISPLAY INVISIBLE (-765 10);
FORCEPROP 1 LASTPIN (-775 0) BN 7
J 2
(-763 8);
DISPLAY 0.680851 (-763 8);
PAINT GREEN (-763 8);
FORCEPROP 2 LAST CDS_LIB standard
J 0
(-825 0);
DISPLAY INVISIBLE (-825 0);
FORCEPROP 1 LAST BODY_TYPE PLUMBING
J 2
(-825 50);
DISPLAY 0.872340 (-825 50);
PAINT GREEN (-825 50);
DISPLAY INVISIBLE (-825 50);
FORCEPROP 1 LAST HDL_TAP TRUE
J 2
(-1150 -125);
DISPLAY 0.872340 (-1150 -125);
DISPLAY INVISIBLE (-1150 -125);
FORCEPROP 1 LAST PATH I16
J 2
(-823 0);
DISPLAY 0.872340 (-823 0);
PAINT GREEN (-823 0);
DISPLAY INVISIBLE (-823 0);
FORCEADD OFFPAGE..2
(3700 450);
FORCEPROP 2 LAST $XR1 105 
J 0
(4009 450);
DISPLAY 0.638298 (4009 450);
PAINT MONO (4009 450);
FORCEPROP 2 LAST $XR0 104 
J 0
(3889 450);
DISPLAY 0.638298 (3889 450);
PAINT MONO (3889 450);
FORCEPROP 2 LAST CDS_LIB standard
J 0
(3700 450);
PAINT MONO (3700 450);
DISPLAY INVISIBLE (3700 450);
FORCEPROP 1 LAST OFFPAGE TRUE
J 0
(4025 325);
DISPLAY 1.170213 (4025 325);
PAINT GREEN (4025 325);
DISPLAY INVISIBLE (4025 325);
FORCEPROP 1 LAST COMMENT_BODY TRUE
J 0
(3655 355);
DISPLAY 1.170213 (3655 355);
PAINT GREEN (3655 355);
DISPLAY INVISIBLE (3655 355);
FORCEPROP 2 LAST PATH I160
J 0
(3875 525);
DISPLAY 1.021277 (3875 525);
DISPLAY INVISIBLE (3875 525);
FORCEADD OFFPAGE..2
(3700 325);
FORCEPROP 2 LAST $XR1 105 
J 0
(4009 325);
DISPLAY 0.638298 (4009 325);
PAINT MONO (4009 325);
FORCEPROP 2 LAST $XR0 104 
J 0
(3889 325);
DISPLAY 0.638298 (3889 325);
PAINT MONO (3889 325);
FORCEPROP 2 LAST CDS_LIB standard
J 0
(3700 325);
PAINT MONO (3700 325);
DISPLAY INVISIBLE (3700 325);
FORCEPROP 1 LAST OFFPAGE TRUE
J 0
(4025 200);
DISPLAY 1.170213 (4025 200);
PAINT GREEN (4025 200);
DISPLAY INVISIBLE (4025 200);
FORCEPROP 1 LAST COMMENT_BODY TRUE
J 0
(3655 230);
DISPLAY 1.170213 (3655 230);
PAINT GREEN (3655 230);
DISPLAY INVISIBLE (3655 230);
FORCEPROP 2 LAST PATH I161
J 0
(3875 400);
DISPLAY 1.021277 (3875 400);
DISPLAY INVISIBLE (3875 400);
FORCEADD OFFPAGE..2
(3700 950);
FORCEPROP 2 LAST $XR1 105 
J 0
(4009 950);
DISPLAY 0.638298 (4009 950);
PAINT MONO (4009 950);
FORCEPROP 2 LAST $XR0 104 
J 0
(3889 950);
DISPLAY 0.638298 (3889 950);
PAINT MONO (3889 950);
FORCEPROP 2 LAST CDS_LIB standard
J 0
(3700 950);
PAINT MONO (3700 950);
DISPLAY INVISIBLE (3700 950);
FORCEPROP 1 LAST OFFPAGE TRUE
J 0
(4025 825);
DISPLAY 1.170213 (4025 825);
PAINT GREEN (4025 825);
DISPLAY INVISIBLE (4025 825);
FORCEPROP 1 LAST COMMENT_BODY TRUE
J 0
(3655 855);
DISPLAY 1.170213 (3655 855);
PAINT GREEN (3655 855);
DISPLAY INVISIBLE (3655 855);
FORCEPROP 2 LAST PATH I162
J 0
(3875 1025);
DISPLAY 1.021277 (3875 1025);
DISPLAY INVISIBLE (3875 1025);
FORCEADD OFFPAGE..3
(3700 825);
FORCEPROP 2 LAST $XR1 105 
J 0
(4034 825);
DISPLAY 0.638298 (4034 825);
PAINT MONO (4034 825);
FORCEPROP 2 LAST $XR0 104 
J 0
(3914 825);
DISPLAY 0.638298 (3914 825);
PAINT MONO (3914 825);
FORCEPROP 2 LAST CDS_LIB standard
J 2
(3700 825);
DISPLAY INVISIBLE (3700 825);
FORCEPROP 1 LAST OFFPAGE TRUE
J 0
(4025 700);
DISPLAY 0.872340 (4025 700);
DISPLAY INVISIBLE (4025 700);
FORCEPROP 1 LAST COMMENT_BODY TRUE
J 0
(3650 725);
DISPLAY 0.872340 (3650 725);
PAINT GREEN (3650 725);
DISPLAY INVISIBLE (3650 725);
FORCEPROP 2 LAST PATH I163
J 0
(3900 900);
DISPLAY 1.021277 (3900 900);
DISPLAY INVISIBLE (3900 900);
FORCEADD OFFPAGE..3
(3700 1325);
FORCEPROP 2 LAST $XR1 105 
J 0
(4034 1325);
DISPLAY 0.638298 (4034 1325);
PAINT MONO (4034 1325);
FORCEPROP 2 LAST $XR0 104 
J 0
(3914 1325);
DISPLAY 0.638298 (3914 1325);
PAINT MONO (3914 1325);
FORCEPROP 2 LAST CDS_LIB standard
J 2
(3700 1325);
DISPLAY INVISIBLE (3700 1325);
FORCEPROP 1 LAST OFFPAGE TRUE
J 0
(4025 1200);
DISPLAY 0.872340 (4025 1200);
DISPLAY INVISIBLE (4025 1200);
FORCEPROP 1 LAST COMMENT_BODY TRUE
J 0
(3650 1225);
DISPLAY 0.872340 (3650 1225);
PAINT GREEN (3650 1225);
DISPLAY INVISIBLE (3650 1225);
FORCEPROP 2 LAST PATH I164
J 0
(3900 1400);
DISPLAY 1.021277 (3900 1400);
DISPLAY INVISIBLE (3900 1400);
FORCEADD OFFPAGE..3
(3700 1925);
FORCEPROP 2 LAST $XR1 105 
J 0
(4034 1925);
DISPLAY 0.638298 (4034 1925);
PAINT MONO (4034 1925);
FORCEPROP 2 LAST $XR0 104 
J 0
(3914 1925);
DISPLAY 0.638298 (3914 1925);
PAINT MONO (3914 1925);
FORCEPROP 2 LAST CDS_LIB standard
J 2
(3700 1925);
DISPLAY INVISIBLE (3700 1925);
FORCEPROP 1 LAST OFFPAGE TRUE
J 0
(4025 1800);
DISPLAY 0.872340 (4025 1800);
DISPLAY INVISIBLE (4025 1800);
FORCEPROP 1 LAST COMMENT_BODY TRUE
J 0
(3650 1825);
DISPLAY 0.872340 (3650 1825);
PAINT GREEN (3650 1825);
DISPLAY INVISIBLE (3650 1825);
FORCEPROP 2 LAST PATH I165
J 0
(3900 2000);
DISPLAY 1.021277 (3900 2000);
DISPLAY INVISIBLE (3900 2000);
FORCEADD OFFPAGE..3
(3700 2475);
FORCEPROP 2 LAST $XR1 105 
J 0
(4034 2475);
DISPLAY 0.638298 (4034 2475);
PAINT MONO (4034 2475);
FORCEPROP 2 LAST $XR0 104 
J 0
(3914 2475);
DISPLAY 0.638298 (3914 2475);
PAINT MONO (3914 2475);
FORCEPROP 2 LAST CDS_LIB standard
J 2
(3700 2475);
DISPLAY INVISIBLE (3700 2475);
FORCEPROP 1 LAST OFFPAGE TRUE
J 0
(4025 2350);
DISPLAY 0.872340 (4025 2350);
DISPLAY INVISIBLE (4025 2350);
FORCEPROP 1 LAST COMMENT_BODY TRUE
J 0
(3650 2375);
DISPLAY 0.872340 (3650 2375);
PAINT GREEN (3650 2375);
DISPLAY INVISIBLE (3650 2375);
FORCEPROP 2 LAST PATH I166
J 0
(3900 2550);
DISPLAY 1.021277 (3900 2550);
DISPLAY INVISIBLE (3900 2550);
FORCEADD OFFPAGE..3
(3700 3075);
FORCEPROP 2 LAST $XR1 105 
J 0
(4034 3075);
DISPLAY 0.638298 (4034 3075);
PAINT MONO (4034 3075);
FORCEPROP 2 LAST $XR0 104 
J 0
(3914 3075);
DISPLAY 0.638298 (3914 3075);
PAINT MONO (3914 3075);
FORCEPROP 2 LAST CDS_LIB standard
J 2
(3700 3075);
DISPLAY INVISIBLE (3700 3075);
FORCEPROP 1 LAST OFFPAGE TRUE
J 0
(4025 2950);
DISPLAY 0.872340 (4025 2950);
DISPLAY INVISIBLE (4025 2950);
FORCEPROP 1 LAST COMMENT_BODY TRUE
J 0
(3650 2975);
DISPLAY 0.872340 (3650 2975);
PAINT GREEN (3650 2975);
DISPLAY INVISIBLE (3650 2975);
FORCEPROP 2 LAST PATH I167
J 0
(3900 3150);
DISPLAY 1.021277 (3900 3150);
DISPLAY INVISIBLE (3900 3150);
FORCEADD OFFPAGE..3
(3700 3625);
FORCEPROP 2 LAST $XR1 105 
J 0
(4034 3625);
DISPLAY 0.638298 (4034 3625);
PAINT MONO (4034 3625);
FORCEPROP 2 LAST $XR0 104 
J 0
(3914 3625);
DISPLAY 0.638298 (3914 3625);
PAINT MONO (3914 3625);
FORCEPROP 2 LAST CDS_LIB standard
J 2
(3700 3625);
DISPLAY INVISIBLE (3700 3625);
FORCEPROP 1 LAST OFFPAGE TRUE
J 0
(4025 3500);
DISPLAY 0.872340 (4025 3500);
DISPLAY INVISIBLE (4025 3500);
FORCEPROP 1 LAST COMMENT_BODY TRUE
J 0
(3650 3525);
DISPLAY 0.872340 (3650 3525);
PAINT GREEN (3650 3525);
DISPLAY INVISIBLE (3650 3525);
FORCEPROP 2 LAST PATH I168
J 0
(3900 3700);
DISPLAY 1.021277 (3900 3700);
DISPLAY INVISIBLE (3900 3700);
FORCEADD TAP..1
R 2
(-825 50);
FORCEPROP 3 LASTPIN (-775 50) SIG_NAME M_D_CPU1_SB_DQ<0>
J 0
(-765 60);
DISPLAY 0.659574 (-765 60);
PAINT MONO (-765 60);
DISPLAY INVISIBLE (-765 60);
FORCEPROP 1 LASTPIN (-775 50) BN 0
J 2
(-763 58);
DISPLAY 0.680851 (-763 58);
PAINT GREEN (-763 58);
FORCEPROP 2 LAST CDS_LIB standard
J 0
(-825 50);
DISPLAY INVISIBLE (-825 50);
FORCEPROP 1 LAST BODY_TYPE PLUMBING
J 2
(-825 100);
DISPLAY 0.872340 (-825 100);
PAINT GREEN (-825 100);
DISPLAY INVISIBLE (-825 100);
FORCEPROP 1 LAST HDL_TAP TRUE
J 2
(-1150 -75);
DISPLAY 0.872340 (-1150 -75);
DISPLAY INVISIBLE (-1150 -75);
FORCEPROP 1 LAST PATH I17
J 2
(-823 50);
DISPLAY 0.872340 (-823 50);
PAINT GREEN (-823 50);
DISPLAY INVISIBLE (-823 50);
FORCEADD TAP..1
R 2
(-825 100);
FORCEPROP 3 LASTPIN (-775 100) SIG_NAME M_D_CPU1_SB_DQ<1>
J 0
(-765 110);
DISPLAY 0.659574 (-765 110);
PAINT MONO (-765 110);
DISPLAY INVISIBLE (-765 110);
FORCEPROP 1 LASTPIN (-775 100) BN 1
J 2
(-763 108);
DISPLAY 0.680851 (-763 108);
PAINT GREEN (-763 108);
FORCEPROP 2 LAST CDS_LIB standard
J 0
(-825 100);
DISPLAY INVISIBLE (-825 100);
FORCEPROP 1 LAST BODY_TYPE PLUMBING
J 2
(-825 150);
DISPLAY 0.872340 (-825 150);
PAINT GREEN (-825 150);
DISPLAY INVISIBLE (-825 150);
FORCEPROP 1 LAST HDL_TAP TRUE
J 2
(-1150 -25);
DISPLAY 0.872340 (-1150 -25);
DISPLAY INVISIBLE (-1150 -25);
FORCEPROP 1 LAST PATH I18
J 2
(-823 100);
DISPLAY 0.872340 (-823 100);
PAINT GREEN (-823 100);
DISPLAY INVISIBLE (-823 100);
FORCEADD TAP..1
R 2
(-825 150);
FORCEPROP 3 LASTPIN (-775 150) SIG_NAME M_D_CPU1_SB_DQ<2>
J 0
(-765 160);
DISPLAY 0.659574 (-765 160);
PAINT MONO (-765 160);
DISPLAY INVISIBLE (-765 160);
FORCEPROP 1 LASTPIN (-775 150) BN 2
J 2
(-763 158);
DISPLAY 0.680851 (-763 158);
PAINT GREEN (-763 158);
FORCEPROP 2 LAST CDS_LIB standard
J 0
(-825 150);
DISPLAY INVISIBLE (-825 150);
FORCEPROP 1 LAST BODY_TYPE PLUMBING
J 2
(-825 200);
DISPLAY 0.872340 (-825 200);
PAINT GREEN (-825 200);
DISPLAY INVISIBLE (-825 200);
FORCEPROP 1 LAST HDL_TAP TRUE
J 2
(-1150 25);
DISPLAY 0.872340 (-1150 25);
DISPLAY INVISIBLE (-1150 25);
FORCEPROP 1 LAST PATH I19
J 2
(-823 150);
DISPLAY 0.872340 (-823 150);
PAINT GREEN (-823 150);
DISPLAY INVISIBLE (-823 150);
FORCEADD OFFPAGE..2
R 2
(-1850 -425);
FORCEPROP 2 LAST $XR1 105 
J 0
(-2225 -425);
DISPLAY 0.638298 (-2225 -425);
PAINT MONO (-2225 -425);
FORCEPROP 2 LAST $XR0 104 
J 0
(-2105 -425);
DISPLAY 0.638298 (-2105 -425);
PAINT MONO (-2105 -425);
FORCEPROP 2 LAST CDS_LIB standard
J 0
(-1850 -425);
PAINT MONO (-1850 -425);
DISPLAY INVISIBLE (-1850 -425);
FORCEPROP 1 LAST OFFPAGE TRUE
J 2
(-2175 -550);
DISPLAY 0.872340 (-2175 -550);
DISPLAY INVISIBLE (-2175 -550);
FORCEPROP 1 LAST COMMENT_BODY TRUE
J 2
(-1805 -520);
DISPLAY 0.872340 (-1805 -520);
PAINT GREEN (-1805 -520);
DISPLAY INVISIBLE (-1805 -520);
FORCEPROP 2 LAST PATH I2
J 0
(-1800 -350);
DISPLAY 1.021277 (-1800 -350);
DISPLAY INVISIBLE (-1800 -350);
FORCEADD TAP..1
R 2
(-825 200);
FORCEPROP 3 LASTPIN (-775 200) SIG_NAME M_D_CPU1_SB_DQ<3>
J 0
(-765 210);
DISPLAY 0.659574 (-765 210);
PAINT MONO (-765 210);
DISPLAY INVISIBLE (-765 210);
FORCEPROP 1 LASTPIN (-775 200) BN 3
J 2
(-763 208);
DISPLAY 0.680851 (-763 208);
PAINT GREEN (-763 208);
FORCEPROP 2 LAST CDS_LIB standard
J 0
(-825 200);
DISPLAY INVISIBLE (-825 200);
FORCEPROP 1 LAST BODY_TYPE PLUMBING
J 2
(-825 250);
DISPLAY 0.872340 (-825 250);
PAINT GREEN (-825 250);
DISPLAY INVISIBLE (-825 250);
FORCEPROP 1 LAST HDL_TAP TRUE
J 2
(-1150 75);
DISPLAY 0.872340 (-1150 75);
DISPLAY INVISIBLE (-1150 75);
FORCEPROP 1 LAST PATH I20
J 2
(-823 200);
DISPLAY 0.872340 (-823 200);
PAINT GREEN (-823 200);
DISPLAY INVISIBLE (-823 200);
FORCEADD TAP..1
R 2
(-825 250);
FORCEPROP 3 LASTPIN (-775 250) SIG_NAME M_D_CPU1_SB_DQ<4>
J 0
(-765 260);
DISPLAY 0.659574 (-765 260);
PAINT MONO (-765 260);
DISPLAY INVISIBLE (-765 260);
FORCEPROP 1 LASTPIN (-775 250) BN 4
J 2
(-763 258);
DISPLAY 0.680851 (-763 258);
PAINT GREEN (-763 258);
FORCEPROP 2 LAST CDS_LIB standard
J 0
(-825 250);
DISPLAY INVISIBLE (-825 250);
FORCEPROP 1 LAST BODY_TYPE PLUMBING
J 2
(-825 300);
DISPLAY 0.872340 (-825 300);
PAINT GREEN (-825 300);
DISPLAY INVISIBLE (-825 300);
FORCEPROP 1 LAST HDL_TAP TRUE
J 2
(-1150 125);
DISPLAY 0.872340 (-1150 125);
DISPLAY INVISIBLE (-1150 125);
FORCEPROP 1 LAST PATH I21
J 2
(-823 250);
DISPLAY 0.872340 (-823 250);
PAINT GREEN (-823 250);
DISPLAY INVISIBLE (-823 250);
FORCEADD TAP..1
R 2
(-825 300);
FORCEPROP 3 LASTPIN (-775 300) SIG_NAME M_D_CPU1_SB_DQ<5>
J 0
(-765 310);
DISPLAY 0.659574 (-765 310);
PAINT MONO (-765 310);
DISPLAY INVISIBLE (-765 310);
FORCEPROP 1 LASTPIN (-775 300) BN 5
J 2
(-763 308);
DISPLAY 0.680851 (-763 308);
PAINT GREEN (-763 308);
FORCEPROP 2 LAST CDS_LIB standard
J 0
(-825 300);
DISPLAY INVISIBLE (-825 300);
FORCEPROP 1 LAST BODY_TYPE PLUMBING
J 2
(-825 350);
DISPLAY 0.872340 (-825 350);
PAINT GREEN (-825 350);
DISPLAY INVISIBLE (-825 350);
FORCEPROP 1 LAST HDL_TAP TRUE
J 2
(-1150 175);
DISPLAY 0.872340 (-1150 175);
DISPLAY INVISIBLE (-1150 175);
FORCEPROP 1 LAST PATH I22
J 2
(-823 300);
DISPLAY 0.872340 (-823 300);
PAINT GREEN (-823 300);
DISPLAY INVISIBLE (-823 300);
FORCEADD TAP..1
R 2
(-825 350);
FORCEPROP 3 LASTPIN (-775 350) SIG_NAME M_D_CPU1_SB_DQ<6>
J 0
(-765 360);
DISPLAY 0.659574 (-765 360);
PAINT MONO (-765 360);
DISPLAY INVISIBLE (-765 360);
FORCEPROP 1 LASTPIN (-775 350) BN 6
J 2
(-763 358);
DISPLAY 0.680851 (-763 358);
PAINT GREEN (-763 358);
FORCEPROP 2 LAST CDS_LIB standard
J 0
(-825 350);
DISPLAY INVISIBLE (-825 350);
FORCEPROP 1 LAST BODY_TYPE PLUMBING
J 2
(-825 400);
DISPLAY 0.872340 (-825 400);
PAINT GREEN (-825 400);
DISPLAY INVISIBLE (-825 400);
FORCEPROP 1 LAST HDL_TAP TRUE
J 2
(-1150 225);
DISPLAY 0.872340 (-1150 225);
DISPLAY INVISIBLE (-1150 225);
FORCEPROP 1 LAST PATH I23
J 2
(-823 350);
DISPLAY 0.872340 (-823 350);
PAINT GREEN (-823 350);
DISPLAY INVISIBLE (-823 350);
FORCEADD TAP..1
R 2
(-825 400);
FORCEPROP 3 LASTPIN (-775 400) SIG_NAME M_D_CPU1_SB_DQ<7>
J 0
(-765 410);
DISPLAY 0.659574 (-765 410);
PAINT MONO (-765 410);
DISPLAY INVISIBLE (-765 410);
FORCEPROP 1 LASTPIN (-775 400) BN 7
J 2
(-763 408);
DISPLAY 0.680851 (-763 408);
PAINT GREEN (-763 408);
FORCEPROP 2 LAST CDS_LIB standard
J 0
(-825 400);
DISPLAY INVISIBLE (-825 400);
FORCEPROP 1 LAST BODY_TYPE PLUMBING
J 2
(-825 450);
DISPLAY 0.872340 (-825 450);
PAINT GREEN (-825 450);
DISPLAY INVISIBLE (-825 450);
FORCEPROP 1 LAST HDL_TAP TRUE
J 2
(-1150 275);
DISPLAY 0.872340 (-1150 275);
DISPLAY INVISIBLE (-1150 275);
FORCEPROP 1 LAST PATH I24
J 2
(-823 400);
DISPLAY 0.872340 (-823 400);
PAINT GREEN (-823 400);
DISPLAY INVISIBLE (-823 400);
FORCEADD TAP..1
R 2
(-825 450);
FORCEPROP 3 LASTPIN (-775 450) SIG_NAME M_D_CPU1_SB_DQ<8>
J 0
(-765 460);
DISPLAY 0.659574 (-765 460);
PAINT MONO (-765 460);
DISPLAY INVISIBLE (-765 460);
FORCEPROP 1 LASTPIN (-775 450) BN 8
J 2
(-763 458);
DISPLAY 0.680851 (-763 458);
PAINT GREEN (-763 458);
FORCEPROP 2 LAST CDS_LIB standard
J 0
(-825 450);
DISPLAY INVISIBLE (-825 450);
FORCEPROP 1 LAST BODY_TYPE PLUMBING
J 2
(-825 500);
DISPLAY 0.872340 (-825 500);
PAINT GREEN (-825 500);
DISPLAY INVISIBLE (-825 500);
FORCEPROP 1 LAST HDL_TAP TRUE
J 2
(-1150 325);
DISPLAY 0.872340 (-1150 325);
DISPLAY INVISIBLE (-1150 325);
FORCEPROP 1 LAST PATH I25
J 2
(-823 450);
DISPLAY 0.872340 (-823 450);
PAINT GREEN (-823 450);
DISPLAY INVISIBLE (-823 450);
FORCEADD TAP..1
R 2
(-825 500);
FORCEPROP 3 LASTPIN (-775 500) SIG_NAME M_D_CPU1_SB_DQ<9>
J 0
(-765 510);
DISPLAY 0.659574 (-765 510);
PAINT MONO (-765 510);
DISPLAY INVISIBLE (-765 510);
FORCEPROP 1 LASTPIN (-775 500) BN 9
J 2
(-763 508);
DISPLAY 0.680851 (-763 508);
PAINT GREEN (-763 508);
FORCEPROP 2 LAST CDS_LIB standard
J 0
(-825 500);
DISPLAY INVISIBLE (-825 500);
FORCEPROP 1 LAST BODY_TYPE PLUMBING
J 2
(-825 550);
DISPLAY 0.872340 (-825 550);
PAINT GREEN (-825 550);
DISPLAY INVISIBLE (-825 550);
FORCEPROP 1 LAST HDL_TAP TRUE
J 2
(-1150 375);
DISPLAY 0.872340 (-1150 375);
DISPLAY INVISIBLE (-1150 375);
FORCEPROP 1 LAST PATH I26
J 2
(-823 500);
DISPLAY 0.872340 (-823 500);
PAINT GREEN (-823 500);
DISPLAY INVISIBLE (-823 500);
FORCEADD TAP..1
R 2
(-825 550);
FORCEPROP 3 LASTPIN (-775 550) SIG_NAME M_D_CPU1_SB_DQ<10>
J 0
(-765 560);
DISPLAY 0.659574 (-765 560);
PAINT MONO (-765 560);
DISPLAY INVISIBLE (-765 560);
FORCEPROP 1 LASTPIN (-775 550) BN 10
J 2
(-763 558);
DISPLAY 0.680851 (-763 558);
PAINT GREEN (-763 558);
FORCEPROP 2 LAST CDS_LIB standard
J 0
(-825 550);
DISPLAY INVISIBLE (-825 550);
FORCEPROP 1 LAST BODY_TYPE PLUMBING
J 2
(-825 600);
DISPLAY 0.872340 (-825 600);
PAINT GREEN (-825 600);
DISPLAY INVISIBLE (-825 600);
FORCEPROP 1 LAST HDL_TAP TRUE
J 2
(-1150 425);
DISPLAY 0.872340 (-1150 425);
DISPLAY INVISIBLE (-1150 425);
FORCEPROP 1 LAST PATH I27
J 2
(-823 550);
DISPLAY 0.872340 (-823 550);
PAINT GREEN (-823 550);
DISPLAY INVISIBLE (-823 550);
FORCEADD TAP..1
R 2
(-825 600);
FORCEPROP 3 LASTPIN (-775 600) SIG_NAME M_D_CPU1_SB_DQ<11>
J 0
(-765 610);
DISPLAY 0.659574 (-765 610);
PAINT MONO (-765 610);
DISPLAY INVISIBLE (-765 610);
FORCEPROP 1 LASTPIN (-775 600) BN 11
J 2
(-763 608);
DISPLAY 0.680851 (-763 608);
PAINT GREEN (-763 608);
FORCEPROP 2 LAST CDS_LIB standard
J 0
(-825 600);
DISPLAY INVISIBLE (-825 600);
FORCEPROP 1 LAST BODY_TYPE PLUMBING
J 2
(-825 650);
DISPLAY 0.872340 (-825 650);
PAINT GREEN (-825 650);
DISPLAY INVISIBLE (-825 650);
FORCEPROP 1 LAST HDL_TAP TRUE
J 2
(-1150 475);
DISPLAY 0.872340 (-1150 475);
DISPLAY INVISIBLE (-1150 475);
FORCEPROP 1 LAST PATH I28
J 2
(-823 600);
DISPLAY 0.872340 (-823 600);
PAINT GREEN (-823 600);
DISPLAY INVISIBLE (-823 600);
FORCEADD TAP..1
R 2
(-825 650);
FORCEPROP 3 LASTPIN (-775 650) SIG_NAME M_D_CPU1_SB_DQ<12>
J 0
(-765 660);
DISPLAY 0.659574 (-765 660);
PAINT MONO (-765 660);
DISPLAY INVISIBLE (-765 660);
FORCEPROP 1 LASTPIN (-775 650) BN 12
J 2
(-763 658);
DISPLAY 0.680851 (-763 658);
PAINT GREEN (-763 658);
FORCEPROP 2 LAST CDS_LIB standard
J 0
(-825 650);
DISPLAY INVISIBLE (-825 650);
FORCEPROP 1 LAST BODY_TYPE PLUMBING
J 2
(-825 700);
DISPLAY 0.872340 (-825 700);
PAINT GREEN (-825 700);
DISPLAY INVISIBLE (-825 700);
FORCEPROP 1 LAST HDL_TAP TRUE
J 2
(-1150 525);
DISPLAY 0.872340 (-1150 525);
DISPLAY INVISIBLE (-1150 525);
FORCEPROP 1 LAST PATH I29
J 2
(-823 650);
DISPLAY 0.872340 (-823 650);
PAINT GREEN (-823 650);
DISPLAY INVISIBLE (-823 650);
FORCEADD TAP..1
R 2
(-825 -600);
FORCEPROP 3 LASTPIN (-775 -600) SIG_NAME M_D_CPU1_CLK_DN<0>
J 0
(-765 -590);
DISPLAY 0.659574 (-765 -590);
PAINT MONO (-765 -590);
DISPLAY INVISIBLE (-765 -590);
FORCEPROP 1 LASTPIN (-775 -600) BN 0
J 2
(-763 -592);
DISPLAY 0.680851 (-763 -592);
PAINT GREEN (-763 -592);
FORCEPROP 2 LAST CDS_LIB standard
J 0
(-825 -600);
DISPLAY INVISIBLE (-825 -600);
FORCEPROP 1 LAST BODY_TYPE PLUMBING
J 2
(-825 -550);
DISPLAY 0.872340 (-825 -550);
PAINT GREEN (-825 -550);
DISPLAY INVISIBLE (-825 -550);
FORCEPROP 1 LAST HDL_TAP TRUE
J 2
(-1150 -725);
DISPLAY 0.872340 (-1150 -725);
DISPLAY INVISIBLE (-1150 -725);
FORCEPROP 1 LAST PATH I3
J 2
(-823 -600);
DISPLAY 0.872340 (-823 -600);
PAINT GREEN (-823 -600);
DISPLAY INVISIBLE (-823 -600);
FORCEADD TAP..1
R 2
(-825 700);
FORCEPROP 3 LASTPIN (-775 700) SIG_NAME M_D_CPU1_SB_DQ<13>
J 0
(-765 710);
DISPLAY 0.659574 (-765 710);
PAINT MONO (-765 710);
DISPLAY INVISIBLE (-765 710);
FORCEPROP 1 LASTPIN (-775 700) BN 13
J 2
(-763 708);
DISPLAY 0.680851 (-763 708);
PAINT GREEN (-763 708);
FORCEPROP 2 LAST CDS_LIB standard
J 0
(-825 700);
DISPLAY INVISIBLE (-825 700);
FORCEPROP 1 LAST BODY_TYPE PLUMBING
J 2
(-825 750);
DISPLAY 0.872340 (-825 750);
PAINT GREEN (-825 750);
DISPLAY INVISIBLE (-825 750);
FORCEPROP 1 LAST HDL_TAP TRUE
J 2
(-1150 575);
DISPLAY 0.872340 (-1150 575);
DISPLAY INVISIBLE (-1150 575);
FORCEPROP 1 LAST PATH I30
J 2
(-823 700);
DISPLAY 0.872340 (-823 700);
PAINT GREEN (-823 700);
DISPLAY INVISIBLE (-823 700);
FORCEADD TAP..1
R 2
(-825 750);
FORCEPROP 3 LASTPIN (-775 750) SIG_NAME M_D_CPU1_SB_DQ<14>
J 0
(-765 760);
DISPLAY 0.659574 (-765 760);
PAINT MONO (-765 760);
DISPLAY INVISIBLE (-765 760);
FORCEPROP 1 LASTPIN (-775 750) BN 14
J 2
(-763 758);
DISPLAY 0.680851 (-763 758);
PAINT GREEN (-763 758);
FORCEPROP 2 LAST CDS_LIB standard
J 0
(-825 750);
DISPLAY INVISIBLE (-825 750);
FORCEPROP 1 LAST BODY_TYPE PLUMBING
J 2
(-825 800);
DISPLAY 0.872340 (-825 800);
PAINT GREEN (-825 800);
DISPLAY INVISIBLE (-825 800);
FORCEPROP 1 LAST HDL_TAP TRUE
J 2
(-1150 625);
DISPLAY 0.872340 (-1150 625);
DISPLAY INVISIBLE (-1150 625);
FORCEPROP 1 LAST PATH I31
J 2
(-823 750);
DISPLAY 0.872340 (-823 750);
PAINT GREEN (-823 750);
DISPLAY INVISIBLE (-823 750);
FORCEADD TAP..1
R 2
(-825 800);
FORCEPROP 3 LASTPIN (-775 800) SIG_NAME M_D_CPU1_SB_DQ<15>
J 0
(-765 810);
DISPLAY 0.659574 (-765 810);
PAINT MONO (-765 810);
DISPLAY INVISIBLE (-765 810);
FORCEPROP 1 LASTPIN (-775 800) BN 15
J 2
(-763 808);
DISPLAY 0.680851 (-763 808);
PAINT GREEN (-763 808);
FORCEPROP 2 LAST CDS_LIB standard
J 0
(-825 800);
DISPLAY INVISIBLE (-825 800);
FORCEPROP 1 LAST BODY_TYPE PLUMBING
J 2
(-825 850);
DISPLAY 0.872340 (-825 850);
PAINT GREEN (-825 850);
DISPLAY INVISIBLE (-825 850);
FORCEPROP 1 LAST HDL_TAP TRUE
J 2
(-1150 675);
DISPLAY 0.872340 (-1150 675);
DISPLAY INVISIBLE (-1150 675);
FORCEPROP 1 LAST PATH I32
J 2
(-823 800);
DISPLAY 0.872340 (-823 800);
PAINT GREEN (-823 800);
DISPLAY INVISIBLE (-823 800);
FORCEADD TAP..1
R 2
(-825 850);
FORCEPROP 3 LASTPIN (-775 850) SIG_NAME M_D_CPU1_SB_DQ<16>
J 0
(-765 860);
DISPLAY 0.659574 (-765 860);
PAINT MONO (-765 860);
DISPLAY INVISIBLE (-765 860);
FORCEPROP 1 LASTPIN (-775 850) BN 16
J 2
(-763 858);
DISPLAY 0.680851 (-763 858);
PAINT GREEN (-763 858);
FORCEPROP 2 LAST CDS_LIB standard
J 0
(-825 850);
DISPLAY INVISIBLE (-825 850);
FORCEPROP 1 LAST BODY_TYPE PLUMBING
J 2
(-825 900);
DISPLAY 0.872340 (-825 900);
PAINT GREEN (-825 900);
DISPLAY INVISIBLE (-825 900);
FORCEPROP 1 LAST HDL_TAP TRUE
J 2
(-1150 725);
DISPLAY 0.872340 (-1150 725);
DISPLAY INVISIBLE (-1150 725);
FORCEPROP 1 LAST PATH I33
J 2
(-823 850);
DISPLAY 0.872340 (-823 850);
PAINT GREEN (-823 850);
DISPLAY INVISIBLE (-823 850);
FORCEADD TAP..1
R 2
(-825 900);
FORCEPROP 3 LASTPIN (-775 900) SIG_NAME M_D_CPU1_SB_DQ<17>
J 0
(-765 910);
DISPLAY 0.659574 (-765 910);
PAINT MONO (-765 910);
DISPLAY INVISIBLE (-765 910);
FORCEPROP 1 LASTPIN (-775 900) BN 17
J 2
(-763 908);
DISPLAY 0.680851 (-763 908);
PAINT GREEN (-763 908);
FORCEPROP 2 LAST CDS_LIB standard
J 0
(-825 900);
DISPLAY INVISIBLE (-825 900);
FORCEPROP 1 LAST BODY_TYPE PLUMBING
J 2
(-825 950);
DISPLAY 0.872340 (-825 950);
PAINT GREEN (-825 950);
DISPLAY INVISIBLE (-825 950);
FORCEPROP 1 LAST HDL_TAP TRUE
J 2
(-1150 775);
DISPLAY 0.872340 (-1150 775);
DISPLAY INVISIBLE (-1150 775);
FORCEPROP 1 LAST PATH I34
J 2
(-823 900);
DISPLAY 0.872340 (-823 900);
PAINT GREEN (-823 900);
DISPLAY INVISIBLE (-823 900);
FORCEADD TAP..1
R 2
(-825 950);
FORCEPROP 3 LASTPIN (-775 950) SIG_NAME M_D_CPU1_SB_DQ<18>
J 0
(-765 960);
DISPLAY 0.659574 (-765 960);
PAINT MONO (-765 960);
DISPLAY INVISIBLE (-765 960);
FORCEPROP 1 LASTPIN (-775 950) BN 18
J 2
(-763 958);
DISPLAY 0.680851 (-763 958);
PAINT GREEN (-763 958);
FORCEPROP 2 LAST CDS_LIB standard
J 0
(-825 950);
DISPLAY INVISIBLE (-825 950);
FORCEPROP 1 LAST BODY_TYPE PLUMBING
J 2
(-825 1000);
DISPLAY 0.872340 (-825 1000);
PAINT GREEN (-825 1000);
DISPLAY INVISIBLE (-825 1000);
FORCEPROP 1 LAST HDL_TAP TRUE
J 2
(-1150 825);
DISPLAY 0.872340 (-1150 825);
DISPLAY INVISIBLE (-1150 825);
FORCEPROP 1 LAST PATH I35
J 2
(-823 950);
DISPLAY 0.872340 (-823 950);
PAINT GREEN (-823 950);
DISPLAY INVISIBLE (-823 950);
FORCEADD TAP..1
R 2
(-825 1000);
FORCEPROP 3 LASTPIN (-775 1000) SIG_NAME M_D_CPU1_SB_DQ<19>
J 0
(-765 1010);
DISPLAY 0.659574 (-765 1010);
PAINT MONO (-765 1010);
DISPLAY INVISIBLE (-765 1010);
FORCEPROP 1 LASTPIN (-775 1000) BN 19
J 2
(-763 1008);
DISPLAY 0.680851 (-763 1008);
PAINT GREEN (-763 1008);
FORCEPROP 2 LAST CDS_LIB standard
J 0
(-825 1000);
DISPLAY INVISIBLE (-825 1000);
FORCEPROP 1 LAST BODY_TYPE PLUMBING
J 2
(-825 1050);
DISPLAY 0.872340 (-825 1050);
PAINT GREEN (-825 1050);
DISPLAY INVISIBLE (-825 1050);
FORCEPROP 1 LAST HDL_TAP TRUE
J 2
(-1150 875);
DISPLAY 0.872340 (-1150 875);
DISPLAY INVISIBLE (-1150 875);
FORCEPROP 1 LAST PATH I36
J 2
(-823 1000);
DISPLAY 0.872340 (-823 1000);
PAINT GREEN (-823 1000);
DISPLAY INVISIBLE (-823 1000);
FORCEADD TAP..1
R 2
(-825 1050);
FORCEPROP 3 LASTPIN (-775 1050) SIG_NAME M_D_CPU1_SB_DQ<20>
J 0
(-765 1060);
DISPLAY 0.659574 (-765 1060);
PAINT MONO (-765 1060);
DISPLAY INVISIBLE (-765 1060);
FORCEPROP 1 LASTPIN (-775 1050) BN 20
J 2
(-763 1058);
DISPLAY 0.680851 (-763 1058);
PAINT GREEN (-763 1058);
FORCEPROP 2 LAST CDS_LIB standard
J 0
(-825 1050);
DISPLAY INVISIBLE (-825 1050);
FORCEPROP 1 LAST BODY_TYPE PLUMBING
J 2
(-825 1100);
DISPLAY 0.872340 (-825 1100);
PAINT GREEN (-825 1100);
DISPLAY INVISIBLE (-825 1100);
FORCEPROP 1 LAST HDL_TAP TRUE
J 2
(-1150 925);
DISPLAY 0.872340 (-1150 925);
DISPLAY INVISIBLE (-1150 925);
FORCEPROP 1 LAST PATH I37
J 2
(-823 1050);
DISPLAY 0.872340 (-823 1050);
PAINT GREEN (-823 1050);
DISPLAY INVISIBLE (-823 1050);
FORCEADD TAP..1
R 2
(-825 1100);
FORCEPROP 3 LASTPIN (-775 1100) SIG_NAME M_D_CPU1_SB_DQ<21>
J 0
(-765 1110);
DISPLAY 0.659574 (-765 1110);
PAINT MONO (-765 1110);
DISPLAY INVISIBLE (-765 1110);
FORCEPROP 1 LASTPIN (-775 1100) BN 21
J 2
(-763 1108);
DISPLAY 0.680851 (-763 1108);
PAINT GREEN (-763 1108);
FORCEPROP 2 LAST CDS_LIB standard
J 0
(-825 1100);
DISPLAY INVISIBLE (-825 1100);
FORCEPROP 1 LAST BODY_TYPE PLUMBING
J 2
(-825 1150);
DISPLAY 0.872340 (-825 1150);
PAINT GREEN (-825 1150);
DISPLAY INVISIBLE (-825 1150);
FORCEPROP 1 LAST HDL_TAP TRUE
J 2
(-1150 975);
DISPLAY 0.872340 (-1150 975);
DISPLAY INVISIBLE (-1150 975);
FORCEPROP 1 LAST PATH I38
J 2
(-823 1100);
DISPLAY 0.872340 (-823 1100);
PAINT GREEN (-823 1100);
DISPLAY INVISIBLE (-823 1100);
FORCEADD TAP..1
R 2
(-825 1150);
FORCEPROP 3 LASTPIN (-775 1150) SIG_NAME M_D_CPU1_SB_DQ<22>
J 0
(-765 1160);
DISPLAY 0.659574 (-765 1160);
PAINT MONO (-765 1160);
DISPLAY INVISIBLE (-765 1160);
FORCEPROP 1 LASTPIN (-775 1150) BN 22
J 2
(-763 1158);
DISPLAY 0.680851 (-763 1158);
PAINT GREEN (-763 1158);
FORCEPROP 2 LAST CDS_LIB standard
J 0
(-825 1150);
DISPLAY INVISIBLE (-825 1150);
FORCEPROP 1 LAST BODY_TYPE PLUMBING
J 2
(-825 1200);
DISPLAY 0.872340 (-825 1200);
PAINT GREEN (-825 1200);
DISPLAY INVISIBLE (-825 1200);
FORCEPROP 1 LAST HDL_TAP TRUE
J 2
(-1150 1025);
DISPLAY 0.872340 (-1150 1025);
DISPLAY INVISIBLE (-1150 1025);
FORCEPROP 1 LAST PATH I39
J 2
(-823 1150);
DISPLAY 0.872340 (-823 1150);
PAINT GREEN (-823 1150);
DISPLAY INVISIBLE (-823 1150);
FORCEADD TAP..1
R 2
(-825 -500);
FORCEPROP 3 LASTPIN (-775 -500) SIG_NAME M_D_CPU1_CLK_DP<0>
J 0
(-765 -490);
DISPLAY 0.659574 (-765 -490);
PAINT MONO (-765 -490);
DISPLAY INVISIBLE (-765 -490);
FORCEPROP 1 LASTPIN (-775 -500) BN 0
J 2
(-763 -492);
DISPLAY 0.680851 (-763 -492);
PAINT GREEN (-763 -492);
FORCEPROP 2 LAST CDS_LIB standard
J 0
(-825 -500);
DISPLAY INVISIBLE (-825 -500);
FORCEPROP 1 LAST BODY_TYPE PLUMBING
J 2
(-825 -450);
DISPLAY 0.872340 (-825 -450);
PAINT GREEN (-825 -450);
DISPLAY INVISIBLE (-825 -450);
FORCEPROP 1 LAST HDL_TAP TRUE
J 2
(-1150 -625);
DISPLAY 0.872340 (-1150 -625);
DISPLAY INVISIBLE (-1150 -625);
FORCEPROP 1 LAST PATH I4
J 2
(-823 -500);
DISPLAY 0.872340 (-823 -500);
PAINT GREEN (-823 -500);
DISPLAY INVISIBLE (-823 -500);
FORCEADD TAP..1
R 2
(-825 1200);
FORCEPROP 3 LASTPIN (-775 1200) SIG_NAME M_D_CPU1_SB_DQ<23>
J 0
(-765 1210);
DISPLAY 0.659574 (-765 1210);
PAINT MONO (-765 1210);
DISPLAY INVISIBLE (-765 1210);
FORCEPROP 1 LASTPIN (-775 1200) BN 23
J 2
(-763 1208);
DISPLAY 0.680851 (-763 1208);
PAINT GREEN (-763 1208);
FORCEPROP 2 LAST CDS_LIB standard
J 0
(-825 1200);
DISPLAY INVISIBLE (-825 1200);
FORCEPROP 1 LAST BODY_TYPE PLUMBING
J 2
(-825 1250);
DISPLAY 0.872340 (-825 1250);
PAINT GREEN (-825 1250);
DISPLAY INVISIBLE (-825 1250);
FORCEPROP 1 LAST HDL_TAP TRUE
J 2
(-1150 1075);
DISPLAY 0.872340 (-1150 1075);
DISPLAY INVISIBLE (-1150 1075);
FORCEPROP 1 LAST PATH I40
J 2
(-823 1200);
DISPLAY 0.872340 (-823 1200);
PAINT GREEN (-823 1200);
DISPLAY INVISIBLE (-823 1200);
FORCEADD TAP..1
R 2
(-825 1250);
FORCEPROP 3 LASTPIN (-775 1250) SIG_NAME M_D_CPU1_SB_DQ<24>
J 0
(-765 1260);
DISPLAY 0.659574 (-765 1260);
PAINT MONO (-765 1260);
DISPLAY INVISIBLE (-765 1260);
FORCEPROP 1 LASTPIN (-775 1250) BN 24
J 2
(-763 1258);
DISPLAY 0.680851 (-763 1258);
PAINT GREEN (-763 1258);
FORCEPROP 2 LAST CDS_LIB standard
J 0
(-825 1250);
DISPLAY INVISIBLE (-825 1250);
FORCEPROP 1 LAST BODY_TYPE PLUMBING
J 2
(-825 1300);
DISPLAY 0.872340 (-825 1300);
PAINT GREEN (-825 1300);
DISPLAY INVISIBLE (-825 1300);
FORCEPROP 1 LAST HDL_TAP TRUE
J 2
(-1150 1125);
DISPLAY 0.872340 (-1150 1125);
DISPLAY INVISIBLE (-1150 1125);
FORCEPROP 1 LAST PATH I41
J 2
(-823 1250);
DISPLAY 0.872340 (-823 1250);
PAINT GREEN (-823 1250);
DISPLAY INVISIBLE (-823 1250);
FORCEADD TAP..1
R 2
(-825 1300);
FORCEPROP 3 LASTPIN (-775 1300) SIG_NAME M_D_CPU1_SB_DQ<25>
J 0
(-765 1310);
DISPLAY 0.659574 (-765 1310);
PAINT MONO (-765 1310);
DISPLAY INVISIBLE (-765 1310);
FORCEPROP 1 LASTPIN (-775 1300) BN 25
J 2
(-763 1308);
DISPLAY 0.680851 (-763 1308);
PAINT GREEN (-763 1308);
FORCEPROP 2 LAST CDS_LIB standard
J 0
(-825 1300);
DISPLAY INVISIBLE (-825 1300);
FORCEPROP 1 LAST BODY_TYPE PLUMBING
J 2
(-825 1350);
DISPLAY 0.872340 (-825 1350);
PAINT GREEN (-825 1350);
DISPLAY INVISIBLE (-825 1350);
FORCEPROP 1 LAST HDL_TAP TRUE
J 2
(-1150 1175);
DISPLAY 0.872340 (-1150 1175);
DISPLAY INVISIBLE (-1150 1175);
FORCEPROP 1 LAST PATH I42
J 2
(-823 1300);
DISPLAY 0.872340 (-823 1300);
PAINT GREEN (-823 1300);
DISPLAY INVISIBLE (-823 1300);
FORCEADD TAP..1
R 2
(-825 1350);
FORCEPROP 3 LASTPIN (-775 1350) SIG_NAME M_D_CPU1_SB_DQ<26>
J 0
(-765 1360);
DISPLAY 0.659574 (-765 1360);
PAINT MONO (-765 1360);
DISPLAY INVISIBLE (-765 1360);
FORCEPROP 1 LASTPIN (-775 1350) BN 26
J 2
(-763 1358);
DISPLAY 0.680851 (-763 1358);
PAINT GREEN (-763 1358);
FORCEPROP 2 LAST CDS_LIB standard
J 0
(-825 1350);
DISPLAY INVISIBLE (-825 1350);
FORCEPROP 1 LAST BODY_TYPE PLUMBING
J 2
(-825 1400);
DISPLAY 0.872340 (-825 1400);
PAINT GREEN (-825 1400);
DISPLAY INVISIBLE (-825 1400);
FORCEPROP 1 LAST HDL_TAP TRUE
J 2
(-1150 1225);
DISPLAY 0.872340 (-1150 1225);
DISPLAY INVISIBLE (-1150 1225);
FORCEPROP 1 LAST PATH I43
J 2
(-823 1350);
DISPLAY 0.872340 (-823 1350);
PAINT GREEN (-823 1350);
DISPLAY INVISIBLE (-823 1350);
FORCEADD TAP..1
R 2
(-825 1400);
FORCEPROP 3 LASTPIN (-775 1400) SIG_NAME M_D_CPU1_SB_DQ<27>
J 0
(-765 1410);
DISPLAY 0.659574 (-765 1410);
PAINT MONO (-765 1410);
DISPLAY INVISIBLE (-765 1410);
FORCEPROP 1 LASTPIN (-775 1400) BN 27
J 2
(-763 1408);
DISPLAY 0.680851 (-763 1408);
PAINT GREEN (-763 1408);
FORCEPROP 2 LAST CDS_LIB standard
J 0
(-825 1400);
DISPLAY INVISIBLE (-825 1400);
FORCEPROP 1 LAST BODY_TYPE PLUMBING
J 2
(-825 1450);
DISPLAY 0.872340 (-825 1450);
PAINT GREEN (-825 1450);
DISPLAY INVISIBLE (-825 1450);
FORCEPROP 1 LAST HDL_TAP TRUE
J 2
(-1150 1275);
DISPLAY 0.872340 (-1150 1275);
DISPLAY INVISIBLE (-1150 1275);
FORCEPROP 1 LAST PATH I44
J 2
(-823 1400);
DISPLAY 0.872340 (-823 1400);
PAINT GREEN (-823 1400);
DISPLAY INVISIBLE (-823 1400);
FORCEADD TAP..1
R 2
(-825 1450);
FORCEPROP 3 LASTPIN (-775 1450) SIG_NAME M_D_CPU1_SB_DQ<28>
J 0
(-765 1460);
DISPLAY 0.659574 (-765 1460);
PAINT MONO (-765 1460);
DISPLAY INVISIBLE (-765 1460);
FORCEPROP 1 LASTPIN (-775 1450) BN 28
J 2
(-763 1458);
DISPLAY 0.680851 (-763 1458);
PAINT GREEN (-763 1458);
FORCEPROP 2 LAST CDS_LIB standard
J 0
(-825 1450);
DISPLAY INVISIBLE (-825 1450);
FORCEPROP 1 LAST BODY_TYPE PLUMBING
J 2
(-825 1500);
DISPLAY 0.872340 (-825 1500);
PAINT GREEN (-825 1500);
DISPLAY INVISIBLE (-825 1500);
FORCEPROP 1 LAST HDL_TAP TRUE
J 2
(-1150 1325);
DISPLAY 0.872340 (-1150 1325);
DISPLAY INVISIBLE (-1150 1325);
FORCEPROP 1 LAST PATH I45
J 2
(-823 1450);
DISPLAY 0.872340 (-823 1450);
PAINT GREEN (-823 1450);
DISPLAY INVISIBLE (-823 1450);
FORCEADD TAP..1
R 2
(-825 1500);
FORCEPROP 3 LASTPIN (-775 1500) SIG_NAME M_D_CPU1_SB_DQ<29>
J 0
(-765 1510);
DISPLAY 0.659574 (-765 1510);
PAINT MONO (-765 1510);
DISPLAY INVISIBLE (-765 1510);
FORCEPROP 1 LASTPIN (-775 1500) BN 29
J 2
(-763 1508);
DISPLAY 0.680851 (-763 1508);
PAINT GREEN (-763 1508);
FORCEPROP 2 LAST CDS_LIB standard
J 0
(-825 1500);
DISPLAY INVISIBLE (-825 1500);
FORCEPROP 1 LAST BODY_TYPE PLUMBING
J 2
(-825 1550);
DISPLAY 0.872340 (-825 1550);
PAINT GREEN (-825 1550);
DISPLAY INVISIBLE (-825 1550);
FORCEPROP 1 LAST HDL_TAP TRUE
J 2
(-1150 1375);
DISPLAY 0.872340 (-1150 1375);
DISPLAY INVISIBLE (-1150 1375);
FORCEPROP 1 LAST PATH I46
J 2
(-823 1500);
DISPLAY 0.872340 (-823 1500);
PAINT GREEN (-823 1500);
DISPLAY INVISIBLE (-823 1500);
FORCEADD TAP..1
R 2
(-825 1550);
FORCEPROP 3 LASTPIN (-775 1550) SIG_NAME M_D_CPU1_SB_DQ<30>
J 0
(-765 1560);
DISPLAY 0.659574 (-765 1560);
PAINT MONO (-765 1560);
DISPLAY INVISIBLE (-765 1560);
FORCEPROP 1 LASTPIN (-775 1550) BN 30
J 2
(-763 1558);
DISPLAY 0.680851 (-763 1558);
PAINT GREEN (-763 1558);
FORCEPROP 2 LAST CDS_LIB standard
J 0
(-825 1550);
DISPLAY INVISIBLE (-825 1550);
FORCEPROP 1 LAST BODY_TYPE PLUMBING
J 2
(-825 1600);
DISPLAY 0.872340 (-825 1600);
PAINT GREEN (-825 1600);
DISPLAY INVISIBLE (-825 1600);
FORCEPROP 1 LAST HDL_TAP TRUE
J 2
(-1150 1425);
DISPLAY 0.872340 (-1150 1425);
DISPLAY INVISIBLE (-1150 1425);
FORCEPROP 1 LAST PATH I47
J 2
(-823 1550);
DISPLAY 0.872340 (-823 1550);
PAINT GREEN (-823 1550);
DISPLAY INVISIBLE (-823 1550);
FORCEADD TAP..1
R 2
(-825 1600);
FORCEPROP 3 LASTPIN (-775 1600) SIG_NAME M_D_CPU1_SB_DQ<31>
J 0
(-765 1610);
DISPLAY 0.659574 (-765 1610);
PAINT MONO (-765 1610);
DISPLAY INVISIBLE (-765 1610);
FORCEPROP 1 LASTPIN (-775 1600) BN 31
J 2
(-763 1608);
DISPLAY 0.680851 (-763 1608);
PAINT GREEN (-763 1608);
FORCEPROP 2 LAST CDS_LIB standard
J 0
(-825 1600);
DISPLAY INVISIBLE (-825 1600);
FORCEPROP 1 LAST BODY_TYPE PLUMBING
J 2
(-825 1650);
DISPLAY 0.872340 (-825 1650);
PAINT GREEN (-825 1650);
DISPLAY INVISIBLE (-825 1650);
FORCEPROP 1 LAST HDL_TAP TRUE
J 2
(-1150 1475);
DISPLAY 0.872340 (-1150 1475);
DISPLAY INVISIBLE (-1150 1475);
FORCEPROP 1 LAST PATH I48
J 2
(-823 1600);
DISPLAY 0.872340 (-823 1600);
PAINT GREEN (-823 1600);
DISPLAY INVISIBLE (-823 1600);
FORCEADD TAP..1
R 2
(-825 1650);
FORCEPROP 3 LASTPIN (-775 1650) SIG_NAME M_D_CPU1_SA_CB<0>
J 0
(-765 1660);
DISPLAY 0.659574 (-765 1660);
PAINT MONO (-765 1660);
DISPLAY INVISIBLE (-765 1660);
FORCEPROP 1 LASTPIN (-775 1650) BN 0
J 2
(-763 1658);
DISPLAY 0.680851 (-763 1658);
PAINT GREEN (-763 1658);
FORCEPROP 2 LAST CDS_LIB standard
J 0
(-825 1650);
DISPLAY INVISIBLE (-825 1650);
FORCEPROP 1 LAST BODY_TYPE PLUMBING
J 2
(-825 1700);
DISPLAY 0.872340 (-825 1700);
PAINT GREEN (-825 1700);
DISPLAY INVISIBLE (-825 1700);
FORCEPROP 1 LAST HDL_TAP TRUE
J 2
(-1150 1525);
DISPLAY 0.872340 (-1150 1525);
DISPLAY INVISIBLE (-1150 1525);
FORCEPROP 1 LAST PATH I49
J 2
(-823 1650);
DISPLAY 0.872340 (-823 1650);
PAINT GREEN (-823 1650);
DISPLAY INVISIBLE (-823 1650);
FORCEADD TAP..1
R 2
(-825 -550);
FORCEPROP 3 LASTPIN (-775 -550) SIG_NAME M_D_CPU1_CLK_DN<1>
J 0
(-765 -540);
DISPLAY 0.659574 (-765 -540);
PAINT MONO (-765 -540);
DISPLAY INVISIBLE (-765 -540);
FORCEPROP 1 LASTPIN (-775 -550) BN 1
J 2
(-763 -542);
DISPLAY 0.680851 (-763 -542);
PAINT GREEN (-763 -542);
FORCEPROP 2 LAST CDS_LIB standard
J 0
(-825 -550);
DISPLAY INVISIBLE (-825 -550);
FORCEPROP 1 LAST BODY_TYPE PLUMBING
J 2
(-825 -500);
DISPLAY 0.872340 (-825 -500);
PAINT GREEN (-825 -500);
DISPLAY INVISIBLE (-825 -500);
FORCEPROP 1 LAST HDL_TAP TRUE
J 2
(-1150 -675);
DISPLAY 0.872340 (-1150 -675);
DISPLAY INVISIBLE (-1150 -675);
FORCEPROP 1 LAST PATH I5
J 2
(-823 -550);
DISPLAY 0.872340 (-823 -550);
PAINT GREEN (-823 -550);
DISPLAY INVISIBLE (-823 -550);
FORCEADD TAP..1
R 2
(-825 1700);
FORCEPROP 3 LASTPIN (-775 1700) SIG_NAME M_D_CPU1_SA_CB<1>
J 0
(-765 1710);
DISPLAY 0.659574 (-765 1710);
PAINT MONO (-765 1710);
DISPLAY INVISIBLE (-765 1710);
FORCEPROP 1 LASTPIN (-775 1700) BN 1
J 2
(-763 1708);
DISPLAY 0.680851 (-763 1708);
PAINT GREEN (-763 1708);
FORCEPROP 2 LAST CDS_LIB standard
J 0
(-825 1700);
DISPLAY INVISIBLE (-825 1700);
FORCEPROP 1 LAST BODY_TYPE PLUMBING
J 2
(-825 1750);
DISPLAY 0.872340 (-825 1750);
PAINT GREEN (-825 1750);
DISPLAY INVISIBLE (-825 1750);
FORCEPROP 1 LAST HDL_TAP TRUE
J 2
(-1150 1575);
DISPLAY 0.872340 (-1150 1575);
DISPLAY INVISIBLE (-1150 1575);
FORCEPROP 1 LAST PATH I50
J 2
(-823 1700);
DISPLAY 0.872340 (-823 1700);
PAINT GREEN (-823 1700);
DISPLAY INVISIBLE (-823 1700);
FORCEADD OFFPAGE..3
R 2
(-1850 2025);
FORCEPROP 2 LAST $XR1 105 
J 0
(-2280 2025);
DISPLAY 0.638298 (-2280 2025);
PAINT MONO (-2280 2025);
FORCEPROP 2 LAST $XR0 104 
J 0
(-2160 2025);
DISPLAY 0.638298 (-2160 2025);
PAINT MONO (-2160 2025);
FORCEPROP 2 LAST CDS_LIB standard
J 0
(-1850 2025);
DISPLAY INVISIBLE (-1850 2025);
FORCEPROP 1 LAST OFFPAGE TRUE
J 2
(-2175 1900);
DISPLAY 0.872340 (-2175 1900);
DISPLAY INVISIBLE (-2175 1900);
FORCEPROP 1 LAST COMMENT_BODY TRUE
J 2
(-1800 1925);
DISPLAY 0.872340 (-1800 1925);
PAINT GREEN (-1800 1925);
DISPLAY INVISIBLE (-1800 1925);
FORCEPROP 2 LAST PATH I51
J 0
(-1800 2100);
DISPLAY 1.021277 (-1800 2100);
DISPLAY INVISIBLE (-1800 2100);
FORCEADD OFFPAGE..3
R 2
(-1850 3625);
FORCEPROP 2 LAST $XR1 105 
J 0
(-2280 3625);
DISPLAY 0.638298 (-2280 3625);
PAINT MONO (-2280 3625);
FORCEPROP 2 LAST $XR0 104 
J 0
(-2160 3625);
DISPLAY 0.638298 (-2160 3625);
PAINT MONO (-2160 3625);
FORCEPROP 2 LAST CDS_LIB standard
J 0
(-1850 3625);
DISPLAY INVISIBLE (-1850 3625);
FORCEPROP 1 LAST OFFPAGE TRUE
J 2
(-2175 3500);
DISPLAY 0.872340 (-2175 3500);
DISPLAY INVISIBLE (-2175 3500);
FORCEPROP 1 LAST COMMENT_BODY TRUE
J 2
(-1800 3525);
DISPLAY 0.872340 (-1800 3525);
PAINT GREEN (-1800 3525);
DISPLAY INVISIBLE (-1800 3525);
FORCEPROP 2 LAST PATH I52
J 0
(-1800 3700);
DISPLAY 1.021277 (-1800 3700);
DISPLAY INVISIBLE (-1800 3700);
FORCEADD TAP..1
R 2
(-825 1750);
FORCEPROP 3 LASTPIN (-775 1750) SIG_NAME M_D_CPU1_SA_CB<2>
J 0
(-765 1760);
DISPLAY 0.659574 (-765 1760);
PAINT MONO (-765 1760);
DISPLAY INVISIBLE (-765 1760);
FORCEPROP 1 LASTPIN (-775 1750) BN 2
J 2
(-763 1758);
DISPLAY 0.680851 (-763 1758);
PAINT GREEN (-763 1758);
FORCEPROP 2 LAST CDS_LIB standard
J 0
(-825 1750);
DISPLAY INVISIBLE (-825 1750);
FORCEPROP 1 LAST BODY_TYPE PLUMBING
J 2
(-825 1800);
DISPLAY 0.872340 (-825 1800);
PAINT GREEN (-825 1800);
DISPLAY INVISIBLE (-825 1800);
FORCEPROP 1 LAST HDL_TAP TRUE
J 2
(-1150 1625);
DISPLAY 0.872340 (-1150 1625);
DISPLAY INVISIBLE (-1150 1625);
FORCEPROP 1 LAST PATH I53
J 2
(-823 1750);
DISPLAY 0.872340 (-823 1750);
PAINT GREEN (-823 1750);
DISPLAY INVISIBLE (-823 1750);
FORCEADD TAP..1
R 2
(-825 1800);
FORCEPROP 3 LASTPIN (-775 1800) SIG_NAME M_D_CPU1_SA_CB<3>
J 0
(-765 1810);
DISPLAY 0.659574 (-765 1810);
PAINT MONO (-765 1810);
DISPLAY INVISIBLE (-765 1810);
FORCEPROP 1 LASTPIN (-775 1800) BN 3
J 2
(-763 1808);
DISPLAY 0.680851 (-763 1808);
PAINT GREEN (-763 1808);
FORCEPROP 2 LAST CDS_LIB standard
J 0
(-825 1800);
DISPLAY INVISIBLE (-825 1800);
FORCEPROP 1 LAST BODY_TYPE PLUMBING
J 2
(-825 1850);
DISPLAY 0.872340 (-825 1850);
PAINT GREEN (-825 1850);
DISPLAY INVISIBLE (-825 1850);
FORCEPROP 1 LAST HDL_TAP TRUE
J 2
(-1150 1675);
DISPLAY 0.872340 (-1150 1675);
DISPLAY INVISIBLE (-1150 1675);
FORCEPROP 1 LAST PATH I54
J 2
(-823 1800);
DISPLAY 0.872340 (-823 1800);
PAINT GREEN (-823 1800);
DISPLAY INVISIBLE (-823 1800);
FORCEADD TAP..1
R 2
(-825 1850);
FORCEPROP 3 LASTPIN (-775 1850) SIG_NAME M_D_CPU1_SA_CB<4>
J 0
(-765 1860);
DISPLAY 0.659574 (-765 1860);
PAINT MONO (-765 1860);
DISPLAY INVISIBLE (-765 1860);
FORCEPROP 1 LASTPIN (-775 1850) BN 4
J 2
(-763 1858);
DISPLAY 0.680851 (-763 1858);
PAINT GREEN (-763 1858);
FORCEPROP 2 LAST CDS_LIB standard
J 0
(-825 1850);
DISPLAY INVISIBLE (-825 1850);
FORCEPROP 1 LAST BODY_TYPE PLUMBING
J 2
(-825 1900);
DISPLAY 0.872340 (-825 1900);
PAINT GREEN (-825 1900);
DISPLAY INVISIBLE (-825 1900);
FORCEPROP 1 LAST HDL_TAP TRUE
J 2
(-1150 1725);
DISPLAY 0.872340 (-1150 1725);
DISPLAY INVISIBLE (-1150 1725);
FORCEPROP 1 LAST PATH I55
J 2
(-823 1850);
DISPLAY 0.872340 (-823 1850);
PAINT GREEN (-823 1850);
DISPLAY INVISIBLE (-823 1850);
FORCEADD TAP..1
R 2
(-825 1900);
FORCEPROP 3 LASTPIN (-775 1900) SIG_NAME M_D_CPU1_SA_CB<5>
J 0
(-765 1910);
DISPLAY 0.659574 (-765 1910);
PAINT MONO (-765 1910);
DISPLAY INVISIBLE (-765 1910);
FORCEPROP 1 LASTPIN (-775 1900) BN 5
J 2
(-763 1908);
DISPLAY 0.680851 (-763 1908);
PAINT GREEN (-763 1908);
FORCEPROP 2 LAST CDS_LIB standard
J 0
(-825 1900);
DISPLAY INVISIBLE (-825 1900);
FORCEPROP 1 LAST BODY_TYPE PLUMBING
J 2
(-825 1950);
DISPLAY 0.872340 (-825 1950);
PAINT GREEN (-825 1950);
DISPLAY INVISIBLE (-825 1950);
FORCEPROP 1 LAST HDL_TAP TRUE
J 2
(-1150 1775);
DISPLAY 0.872340 (-1150 1775);
DISPLAY INVISIBLE (-1150 1775);
FORCEPROP 1 LAST PATH I56
J 2
(-823 1900);
DISPLAY 0.872340 (-823 1900);
PAINT GREEN (-823 1900);
DISPLAY INVISIBLE (-823 1900);
FORCEADD TAP..1
R 2
(-825 1950);
FORCEPROP 3 LASTPIN (-775 1950) SIG_NAME M_D_CPU1_SA_CB<6>
J 0
(-765 1960);
DISPLAY 0.659574 (-765 1960);
PAINT MONO (-765 1960);
DISPLAY INVISIBLE (-765 1960);
FORCEPROP 1 LASTPIN (-775 1950) BN 6
J 2
(-763 1958);
DISPLAY 0.680851 (-763 1958);
PAINT GREEN (-763 1958);
FORCEPROP 2 LAST CDS_LIB standard
J 0
(-825 1950);
DISPLAY INVISIBLE (-825 1950);
FORCEPROP 1 LAST BODY_TYPE PLUMBING
J 2
(-825 2000);
DISPLAY 0.872340 (-825 2000);
PAINT GREEN (-825 2000);
DISPLAY INVISIBLE (-825 2000);
FORCEPROP 1 LAST HDL_TAP TRUE
J 2
(-1150 1825);
DISPLAY 0.872340 (-1150 1825);
DISPLAY INVISIBLE (-1150 1825);
FORCEPROP 1 LAST PATH I57
J 2
(-823 1950);
DISPLAY 0.872340 (-823 1950);
PAINT GREEN (-823 1950);
DISPLAY INVISIBLE (-823 1950);
FORCEADD TAP..1
R 2
(-825 2000);
FORCEPROP 3 LASTPIN (-775 2000) SIG_NAME M_D_CPU1_SA_CB<7>
J 0
(-765 2010);
DISPLAY 0.659574 (-765 2010);
PAINT MONO (-765 2010);
DISPLAY INVISIBLE (-765 2010);
FORCEPROP 1 LASTPIN (-775 2000) BN 7
J 2
(-763 2008);
DISPLAY 0.680851 (-763 2008);
PAINT GREEN (-763 2008);
FORCEPROP 2 LAST CDS_LIB standard
J 0
(-825 2000);
DISPLAY INVISIBLE (-825 2000);
FORCEPROP 1 LAST BODY_TYPE PLUMBING
J 2
(-825 2050);
DISPLAY 0.872340 (-825 2050);
PAINT GREEN (-825 2050);
DISPLAY INVISIBLE (-825 2050);
FORCEPROP 1 LAST HDL_TAP TRUE
J 2
(-1150 1875);
DISPLAY 0.872340 (-1150 1875);
DISPLAY INVISIBLE (-1150 1875);
FORCEPROP 1 LAST PATH I58
J 2
(-823 2000);
DISPLAY 0.872340 (-823 2000);
PAINT GREEN (-823 2000);
DISPLAY INVISIBLE (-823 2000);
FORCEADD TAP..1
R 2
(-825 2100);
FORCEPROP 3 LASTPIN (-775 2100) SIG_NAME M_D_CPU1_SA_DQ<1>
J 0
(-765 2110);
DISPLAY 0.659574 (-765 2110);
PAINT MONO (-765 2110);
DISPLAY INVISIBLE (-765 2110);
FORCEPROP 1 LASTPIN (-775 2100) BN 1
J 2
(-763 2108);
DISPLAY 0.680851 (-763 2108);
PAINT GREEN (-763 2108);
FORCEPROP 2 LAST CDS_LIB standard
J 0
(-825 2100);
DISPLAY INVISIBLE (-825 2100);
FORCEPROP 1 LAST BODY_TYPE PLUMBING
J 2
(-825 2150);
DISPLAY 0.872340 (-825 2150);
PAINT GREEN (-825 2150);
DISPLAY INVISIBLE (-825 2150);
FORCEPROP 1 LAST HDL_TAP TRUE
J 2
(-1150 1975);
DISPLAY 0.872340 (-1150 1975);
DISPLAY INVISIBLE (-1150 1975);
FORCEPROP 1 LAST PATH I59
J 2
(-823 2100);
DISPLAY 0.872340 (-823 2100);
PAINT GREEN (-823 2100);
DISPLAY INVISIBLE (-823 2100);
FORCEADD TAP..1
R 2
(-825 -450);
FORCEPROP 3 LASTPIN (-775 -450) SIG_NAME M_D_CPU1_CLK_DP<1>
J 0
(-765 -440);
DISPLAY 0.659574 (-765 -440);
PAINT MONO (-765 -440);
DISPLAY INVISIBLE (-765 -440);
FORCEPROP 1 LASTPIN (-775 -450) BN 1
J 2
(-763 -442);
DISPLAY 0.680851 (-763 -442);
PAINT GREEN (-763 -442);
FORCEPROP 2 LAST CDS_LIB standard
J 0
(-825 -450);
DISPLAY INVISIBLE (-825 -450);
FORCEPROP 1 LAST BODY_TYPE PLUMBING
J 2
(-825 -400);
DISPLAY 0.872340 (-825 -400);
PAINT GREEN (-825 -400);
DISPLAY INVISIBLE (-825 -400);
FORCEPROP 1 LAST HDL_TAP TRUE
J 2
(-1150 -575);
DISPLAY 0.872340 (-1150 -575);
DISPLAY INVISIBLE (-1150 -575);
FORCEPROP 1 LAST PATH I6
J 2
(-823 -450);
DISPLAY 0.872340 (-823 -450);
PAINT GREEN (-823 -450);
DISPLAY INVISIBLE (-823 -450);
FORCEADD TAP..1
R 2
(-825 2050);
FORCEPROP 3 LASTPIN (-775 2050) SIG_NAME M_D_CPU1_SA_DQ<0>
J 0
(-765 2060);
DISPLAY 0.659574 (-765 2060);
PAINT MONO (-765 2060);
DISPLAY INVISIBLE (-765 2060);
FORCEPROP 1 LASTPIN (-775 2050) BN 0
J 2
(-763 2058);
DISPLAY 0.680851 (-763 2058);
PAINT GREEN (-763 2058);
FORCEPROP 2 LAST CDS_LIB standard
J 0
(-825 2050);
DISPLAY INVISIBLE (-825 2050);
FORCEPROP 1 LAST BODY_TYPE PLUMBING
J 2
(-825 2100);
DISPLAY 0.872340 (-825 2100);
PAINT GREEN (-825 2100);
DISPLAY INVISIBLE (-825 2100);
FORCEPROP 1 LAST HDL_TAP TRUE
J 2
(-1150 1925);
DISPLAY 0.872340 (-1150 1925);
DISPLAY INVISIBLE (-1150 1925);
FORCEPROP 1 LAST PATH I60
J 2
(-823 2050);
DISPLAY 0.872340 (-823 2050);
PAINT GREEN (-823 2050);
DISPLAY INVISIBLE (-823 2050);
FORCEADD TAP..1
R 2
(-825 2150);
FORCEPROP 3 LASTPIN (-775 2150) SIG_NAME M_D_CPU1_SA_DQ<2>
J 0
(-765 2160);
DISPLAY 0.659574 (-765 2160);
PAINT MONO (-765 2160);
DISPLAY INVISIBLE (-765 2160);
FORCEPROP 1 LASTPIN (-775 2150) BN 2
J 2
(-763 2158);
DISPLAY 0.680851 (-763 2158);
PAINT GREEN (-763 2158);
FORCEPROP 2 LAST CDS_LIB standard
J 0
(-825 2150);
DISPLAY INVISIBLE (-825 2150);
FORCEPROP 1 LAST BODY_TYPE PLUMBING
J 2
(-825 2200);
DISPLAY 0.872340 (-825 2200);
PAINT GREEN (-825 2200);
DISPLAY INVISIBLE (-825 2200);
FORCEPROP 1 LAST HDL_TAP TRUE
J 2
(-1150 2025);
DISPLAY 0.872340 (-1150 2025);
DISPLAY INVISIBLE (-1150 2025);
FORCEPROP 1 LAST PATH I61
J 2
(-823 2150);
DISPLAY 0.872340 (-823 2150);
PAINT GREEN (-823 2150);
DISPLAY INVISIBLE (-823 2150);
FORCEADD TAP..1
R 2
(-825 2200);
FORCEPROP 3 LASTPIN (-775 2200) SIG_NAME M_D_CPU1_SA_DQ<3>
J 0
(-765 2210);
DISPLAY 0.659574 (-765 2210);
PAINT MONO (-765 2210);
DISPLAY INVISIBLE (-765 2210);
FORCEPROP 1 LASTPIN (-775 2200) BN 3
J 2
(-763 2208);
DISPLAY 0.680851 (-763 2208);
PAINT GREEN (-763 2208);
FORCEPROP 2 LAST CDS_LIB standard
J 0
(-825 2200);
DISPLAY INVISIBLE (-825 2200);
FORCEPROP 1 LAST BODY_TYPE PLUMBING
J 2
(-825 2250);
DISPLAY 0.872340 (-825 2250);
PAINT GREEN (-825 2250);
DISPLAY INVISIBLE (-825 2250);
FORCEPROP 1 LAST HDL_TAP TRUE
J 2
(-1150 2075);
DISPLAY 0.872340 (-1150 2075);
DISPLAY INVISIBLE (-1150 2075);
FORCEPROP 1 LAST PATH I62
J 2
(-823 2200);
DISPLAY 0.872340 (-823 2200);
PAINT GREEN (-823 2200);
DISPLAY INVISIBLE (-823 2200);
FORCEADD TAP..1
R 2
(-825 2250);
FORCEPROP 3 LASTPIN (-775 2250) SIG_NAME M_D_CPU1_SA_DQ<4>
J 0
(-765 2260);
DISPLAY 0.659574 (-765 2260);
PAINT MONO (-765 2260);
DISPLAY INVISIBLE (-765 2260);
FORCEPROP 1 LASTPIN (-775 2250) BN 4
J 2
(-763 2258);
DISPLAY 0.680851 (-763 2258);
PAINT GREEN (-763 2258);
FORCEPROP 2 LAST CDS_LIB standard
J 0
(-825 2250);
DISPLAY INVISIBLE (-825 2250);
FORCEPROP 1 LAST BODY_TYPE PLUMBING
J 2
(-825 2300);
DISPLAY 0.872340 (-825 2300);
PAINT GREEN (-825 2300);
DISPLAY INVISIBLE (-825 2300);
FORCEPROP 1 LAST HDL_TAP TRUE
J 2
(-1150 2125);
DISPLAY 0.872340 (-1150 2125);
DISPLAY INVISIBLE (-1150 2125);
FORCEPROP 1 LAST PATH I63
J 2
(-823 2250);
DISPLAY 0.872340 (-823 2250);
PAINT GREEN (-823 2250);
DISPLAY INVISIBLE (-823 2250);
FORCEADD TAP..1
R 2
(-825 2300);
FORCEPROP 3 LASTPIN (-775 2300) SIG_NAME M_D_CPU1_SA_DQ<5>
J 0
(-765 2310);
DISPLAY 0.659574 (-765 2310);
PAINT MONO (-765 2310);
DISPLAY INVISIBLE (-765 2310);
FORCEPROP 1 LASTPIN (-775 2300) BN 5
J 2
(-763 2308);
DISPLAY 0.680851 (-763 2308);
PAINT GREEN (-763 2308);
FORCEPROP 2 LAST CDS_LIB standard
J 0
(-825 2300);
DISPLAY INVISIBLE (-825 2300);
FORCEPROP 1 LAST BODY_TYPE PLUMBING
J 2
(-825 2350);
DISPLAY 0.872340 (-825 2350);
PAINT GREEN (-825 2350);
DISPLAY INVISIBLE (-825 2350);
FORCEPROP 1 LAST HDL_TAP TRUE
J 2
(-1150 2175);
DISPLAY 0.872340 (-1150 2175);
DISPLAY INVISIBLE (-1150 2175);
FORCEPROP 1 LAST PATH I64
J 2
(-823 2300);
DISPLAY 0.872340 (-823 2300);
PAINT GREEN (-823 2300);
DISPLAY INVISIBLE (-823 2300);
FORCEADD TAP..1
R 2
(-825 2350);
FORCEPROP 3 LASTPIN (-775 2350) SIG_NAME M_D_CPU1_SA_DQ<6>
J 0
(-765 2360);
DISPLAY 0.659574 (-765 2360);
PAINT MONO (-765 2360);
DISPLAY INVISIBLE (-765 2360);
FORCEPROP 1 LASTPIN (-775 2350) BN 6
J 2
(-763 2358);
DISPLAY 0.680851 (-763 2358);
PAINT GREEN (-763 2358);
FORCEPROP 2 LAST CDS_LIB standard
J 0
(-825 2350);
DISPLAY INVISIBLE (-825 2350);
FORCEPROP 1 LAST BODY_TYPE PLUMBING
J 2
(-825 2400);
DISPLAY 0.872340 (-825 2400);
PAINT GREEN (-825 2400);
DISPLAY INVISIBLE (-825 2400);
FORCEPROP 1 LAST HDL_TAP TRUE
J 2
(-1150 2225);
DISPLAY 0.872340 (-1150 2225);
DISPLAY INVISIBLE (-1150 2225);
FORCEPROP 1 LAST PATH I65
J 2
(-823 2350);
DISPLAY 0.872340 (-823 2350);
PAINT GREEN (-823 2350);
DISPLAY INVISIBLE (-823 2350);
FORCEADD TAP..1
R 2
(-825 2400);
FORCEPROP 3 LASTPIN (-775 2400) SIG_NAME M_D_CPU1_SA_DQ<7>
J 0
(-765 2410);
DISPLAY 0.659574 (-765 2410);
PAINT MONO (-765 2410);
DISPLAY INVISIBLE (-765 2410);
FORCEPROP 1 LASTPIN (-775 2400) BN 7
J 2
(-763 2408);
DISPLAY 0.680851 (-763 2408);
PAINT GREEN (-763 2408);
FORCEPROP 2 LAST CDS_LIB standard
J 0
(-825 2400);
DISPLAY INVISIBLE (-825 2400);
FORCEPROP 1 LAST BODY_TYPE PLUMBING
J 2
(-825 2450);
DISPLAY 0.872340 (-825 2450);
PAINT GREEN (-825 2450);
DISPLAY INVISIBLE (-825 2450);
FORCEPROP 1 LAST HDL_TAP TRUE
J 2
(-1150 2275);
DISPLAY 0.872340 (-1150 2275);
DISPLAY INVISIBLE (-1150 2275);
FORCEPROP 1 LAST PATH I66
J 2
(-823 2400);
DISPLAY 0.872340 (-823 2400);
PAINT GREEN (-823 2400);
DISPLAY INVISIBLE (-823 2400);
FORCEADD TAP..1
R 2
(-825 2450);
FORCEPROP 3 LASTPIN (-775 2450) SIG_NAME M_D_CPU1_SA_DQ<8>
J 0
(-765 2460);
DISPLAY 0.659574 (-765 2460);
PAINT MONO (-765 2460);
DISPLAY INVISIBLE (-765 2460);
FORCEPROP 1 LASTPIN (-775 2450) BN 8
J 2
(-763 2458);
DISPLAY 0.680851 (-763 2458);
PAINT GREEN (-763 2458);
FORCEPROP 2 LAST CDS_LIB standard
J 0
(-825 2450);
DISPLAY INVISIBLE (-825 2450);
FORCEPROP 1 LAST BODY_TYPE PLUMBING
J 2
(-825 2500);
DISPLAY 0.872340 (-825 2500);
PAINT GREEN (-825 2500);
DISPLAY INVISIBLE (-825 2500);
FORCEPROP 1 LAST HDL_TAP TRUE
J 2
(-1150 2325);
DISPLAY 0.872340 (-1150 2325);
DISPLAY INVISIBLE (-1150 2325);
FORCEPROP 1 LAST PATH I67
J 2
(-823 2450);
DISPLAY 0.872340 (-823 2450);
PAINT GREEN (-823 2450);
DISPLAY INVISIBLE (-823 2450);
FORCEADD TAP..1
R 2
(-825 2500);
FORCEPROP 3 LASTPIN (-775 2500) SIG_NAME M_D_CPU1_SA_DQ<9>
J 0
(-765 2510);
DISPLAY 0.659574 (-765 2510);
PAINT MONO (-765 2510);
DISPLAY INVISIBLE (-765 2510);
FORCEPROP 1 LASTPIN (-775 2500) BN 9
J 2
(-763 2508);
DISPLAY 0.680851 (-763 2508);
PAINT GREEN (-763 2508);
FORCEPROP 2 LAST CDS_LIB standard
J 0
(-825 2500);
DISPLAY INVISIBLE (-825 2500);
FORCEPROP 1 LAST BODY_TYPE PLUMBING
J 2
(-825 2550);
DISPLAY 0.872340 (-825 2550);
PAINT GREEN (-825 2550);
DISPLAY INVISIBLE (-825 2550);
FORCEPROP 1 LAST HDL_TAP TRUE
J 2
(-1150 2375);
DISPLAY 0.872340 (-1150 2375);
DISPLAY INVISIBLE (-1150 2375);
FORCEPROP 1 LAST PATH I68
J 2
(-823 2500);
DISPLAY 0.872340 (-823 2500);
PAINT GREEN (-823 2500);
DISPLAY INVISIBLE (-823 2500);
FORCEADD TAP..1
R 2
(-825 2550);
FORCEPROP 3 LASTPIN (-775 2550) SIG_NAME M_D_CPU1_SA_DQ<10>
J 0
(-765 2560);
DISPLAY 0.659574 (-765 2560);
PAINT MONO (-765 2560);
DISPLAY INVISIBLE (-765 2560);
FORCEPROP 1 LASTPIN (-775 2550) BN 10
J 2
(-763 2558);
DISPLAY 0.680851 (-763 2558);
PAINT GREEN (-763 2558);
FORCEPROP 2 LAST CDS_LIB standard
J 0
(-825 2550);
DISPLAY INVISIBLE (-825 2550);
FORCEPROP 1 LAST BODY_TYPE PLUMBING
J 2
(-825 2600);
DISPLAY 0.872340 (-825 2600);
PAINT GREEN (-825 2600);
DISPLAY INVISIBLE (-825 2600);
FORCEPROP 1 LAST HDL_TAP TRUE
J 2
(-1150 2425);
DISPLAY 0.872340 (-1150 2425);
DISPLAY INVISIBLE (-1150 2425);
FORCEPROP 1 LAST PATH I69
J 2
(-823 2550);
DISPLAY 0.872340 (-823 2550);
PAINT GREEN (-823 2550);
DISPLAY INVISIBLE (-823 2550);
FORCEADD TAP..1
R 2
(-825 -350);
FORCEPROP 3 LASTPIN (-775 -350) SIG_NAME M_D_CPU1_SB_CB<0>
J 0
(-765 -340);
DISPLAY 0.659574 (-765 -340);
PAINT MONO (-765 -340);
DISPLAY INVISIBLE (-765 -340);
FORCEPROP 1 LASTPIN (-775 -350) BN 0
J 2
(-763 -342);
DISPLAY 0.680851 (-763 -342);
PAINT GREEN (-763 -342);
FORCEPROP 2 LAST CDS_LIB standard
J 0
(-825 -350);
DISPLAY INVISIBLE (-825 -350);
FORCEPROP 1 LAST BODY_TYPE PLUMBING
J 2
(-825 -300);
DISPLAY 0.872340 (-825 -300);
PAINT GREEN (-825 -300);
DISPLAY INVISIBLE (-825 -300);
FORCEPROP 1 LAST HDL_TAP TRUE
J 2
(-1150 -475);
DISPLAY 0.872340 (-1150 -475);
DISPLAY INVISIBLE (-1150 -475);
FORCEPROP 1 LAST PATH I7
J 2
(-823 -350);
DISPLAY 0.872340 (-823 -350);
PAINT GREEN (-823 -350);
DISPLAY INVISIBLE (-823 -350);
FORCEADD TAP..1
R 2
(-825 2600);
FORCEPROP 3 LASTPIN (-775 2600) SIG_NAME M_D_CPU1_SA_DQ<11>
J 0
(-765 2610);
DISPLAY 0.659574 (-765 2610);
PAINT MONO (-765 2610);
DISPLAY INVISIBLE (-765 2610);
FORCEPROP 1 LASTPIN (-775 2600) BN 11
J 2
(-763 2608);
DISPLAY 0.680851 (-763 2608);
PAINT GREEN (-763 2608);
FORCEPROP 2 LAST CDS_LIB standard
J 0
(-825 2600);
DISPLAY INVISIBLE (-825 2600);
FORCEPROP 1 LAST BODY_TYPE PLUMBING
J 2
(-825 2650);
DISPLAY 0.872340 (-825 2650);
PAINT GREEN (-825 2650);
DISPLAY INVISIBLE (-825 2650);
FORCEPROP 1 LAST HDL_TAP TRUE
J 2
(-1150 2475);
DISPLAY 0.872340 (-1150 2475);
DISPLAY INVISIBLE (-1150 2475);
FORCEPROP 1 LAST PATH I70
J 2
(-823 2600);
DISPLAY 0.872340 (-823 2600);
PAINT GREEN (-823 2600);
DISPLAY INVISIBLE (-823 2600);
FORCEADD TAP..1
R 2
(-825 2650);
FORCEPROP 3 LASTPIN (-775 2650) SIG_NAME M_D_CPU1_SA_DQ<12>
J 0
(-765 2660);
DISPLAY 0.659574 (-765 2660);
PAINT MONO (-765 2660);
DISPLAY INVISIBLE (-765 2660);
FORCEPROP 1 LASTPIN (-775 2650) BN 12
J 2
(-763 2658);
DISPLAY 0.680851 (-763 2658);
PAINT GREEN (-763 2658);
FORCEPROP 2 LAST CDS_LIB standard
J 0
(-825 2650);
DISPLAY INVISIBLE (-825 2650);
FORCEPROP 1 LAST BODY_TYPE PLUMBING
J 2
(-825 2700);
DISPLAY 0.872340 (-825 2700);
PAINT GREEN (-825 2700);
DISPLAY INVISIBLE (-825 2700);
FORCEPROP 1 LAST HDL_TAP TRUE
J 2
(-1150 2525);
DISPLAY 0.872340 (-1150 2525);
DISPLAY INVISIBLE (-1150 2525);
FORCEPROP 1 LAST PATH I71
J 2
(-823 2650);
DISPLAY 0.872340 (-823 2650);
PAINT GREEN (-823 2650);
DISPLAY INVISIBLE (-823 2650);
FORCEADD TAP..1
R 2
(-825 2700);
FORCEPROP 3 LASTPIN (-775 2700) SIG_NAME M_D_CPU1_SA_DQ<13>
J 0
(-765 2710);
DISPLAY 0.659574 (-765 2710);
PAINT MONO (-765 2710);
DISPLAY INVISIBLE (-765 2710);
FORCEPROP 1 LASTPIN (-775 2700) BN 13
J 2
(-763 2708);
DISPLAY 0.680851 (-763 2708);
PAINT GREEN (-763 2708);
FORCEPROP 2 LAST CDS_LIB standard
J 0
(-825 2700);
DISPLAY INVISIBLE (-825 2700);
FORCEPROP 1 LAST BODY_TYPE PLUMBING
J 2
(-825 2750);
DISPLAY 0.872340 (-825 2750);
PAINT GREEN (-825 2750);
DISPLAY INVISIBLE (-825 2750);
FORCEPROP 1 LAST HDL_TAP TRUE
J 2
(-1150 2575);
DISPLAY 0.872340 (-1150 2575);
DISPLAY INVISIBLE (-1150 2575);
FORCEPROP 1 LAST PATH I72
J 2
(-823 2700);
DISPLAY 0.872340 (-823 2700);
PAINT GREEN (-823 2700);
DISPLAY INVISIBLE (-823 2700);
FORCEADD TAP..1
R 2
(-825 2750);
FORCEPROP 3 LASTPIN (-775 2750) SIG_NAME M_D_CPU1_SA_DQ<14>
J 0
(-765 2760);
DISPLAY 0.659574 (-765 2760);
PAINT MONO (-765 2760);
DISPLAY INVISIBLE (-765 2760);
FORCEPROP 1 LASTPIN (-775 2750) BN 14
J 2
(-763 2758);
DISPLAY 0.680851 (-763 2758);
PAINT GREEN (-763 2758);
FORCEPROP 2 LAST CDS_LIB standard
J 0
(-825 2750);
DISPLAY INVISIBLE (-825 2750);
FORCEPROP 1 LAST BODY_TYPE PLUMBING
J 2
(-825 2800);
DISPLAY 0.872340 (-825 2800);
PAINT GREEN (-825 2800);
DISPLAY INVISIBLE (-825 2800);
FORCEPROP 1 LAST HDL_TAP TRUE
J 2
(-1150 2625);
DISPLAY 0.872340 (-1150 2625);
DISPLAY INVISIBLE (-1150 2625);
FORCEPROP 1 LAST PATH I73
J 2
(-823 2750);
DISPLAY 0.872340 (-823 2750);
PAINT GREEN (-823 2750);
DISPLAY INVISIBLE (-823 2750);
FORCEADD TAP..1
R 2
(-825 2800);
FORCEPROP 3 LASTPIN (-775 2800) SIG_NAME M_D_CPU1_SA_DQ<15>
J 0
(-765 2810);
DISPLAY 0.659574 (-765 2810);
PAINT MONO (-765 2810);
DISPLAY INVISIBLE (-765 2810);
FORCEPROP 1 LASTPIN (-775 2800) BN 15
J 2
(-763 2808);
DISPLAY 0.680851 (-763 2808);
PAINT GREEN (-763 2808);
FORCEPROP 2 LAST CDS_LIB standard
J 0
(-825 2800);
DISPLAY INVISIBLE (-825 2800);
FORCEPROP 1 LAST BODY_TYPE PLUMBING
J 2
(-825 2850);
DISPLAY 0.872340 (-825 2850);
PAINT GREEN (-825 2850);
DISPLAY INVISIBLE (-825 2850);
FORCEPROP 1 LAST HDL_TAP TRUE
J 2
(-1150 2675);
DISPLAY 0.872340 (-1150 2675);
DISPLAY INVISIBLE (-1150 2675);
FORCEPROP 1 LAST PATH I74
J 2
(-823 2800);
DISPLAY 0.872340 (-823 2800);
PAINT GREEN (-823 2800);
DISPLAY INVISIBLE (-823 2800);
FORCEADD TAP..1
R 2
(-825 2850);
FORCEPROP 3 LASTPIN (-775 2850) SIG_NAME M_D_CPU1_SA_DQ<16>
J 0
(-765 2860);
DISPLAY 0.659574 (-765 2860);
PAINT MONO (-765 2860);
DISPLAY INVISIBLE (-765 2860);
FORCEPROP 1 LASTPIN (-775 2850) BN 16
J 2
(-763 2858);
DISPLAY 0.680851 (-763 2858);
PAINT GREEN (-763 2858);
FORCEPROP 2 LAST CDS_LIB standard
J 0
(-825 2850);
DISPLAY INVISIBLE (-825 2850);
FORCEPROP 1 LAST BODY_TYPE PLUMBING
J 2
(-825 2900);
DISPLAY 0.872340 (-825 2900);
PAINT GREEN (-825 2900);
DISPLAY INVISIBLE (-825 2900);
FORCEPROP 1 LAST HDL_TAP TRUE
J 2
(-1150 2725);
DISPLAY 0.872340 (-1150 2725);
DISPLAY INVISIBLE (-1150 2725);
FORCEPROP 1 LAST PATH I75
J 2
(-823 2850);
DISPLAY 0.872340 (-823 2850);
PAINT GREEN (-823 2850);
DISPLAY INVISIBLE (-823 2850);
FORCEADD TAP..1
R 2
(-825 2900);
FORCEPROP 3 LASTPIN (-775 2900) SIG_NAME M_D_CPU1_SA_DQ<17>
J 0
(-765 2910);
DISPLAY 0.659574 (-765 2910);
PAINT MONO (-765 2910);
DISPLAY INVISIBLE (-765 2910);
FORCEPROP 1 LASTPIN (-775 2900) BN 17
J 2
(-763 2908);
DISPLAY 0.680851 (-763 2908);
PAINT GREEN (-763 2908);
FORCEPROP 2 LAST CDS_LIB standard
J 0
(-825 2900);
DISPLAY INVISIBLE (-825 2900);
FORCEPROP 1 LAST BODY_TYPE PLUMBING
J 2
(-825 2950);
DISPLAY 0.872340 (-825 2950);
PAINT GREEN (-825 2950);
DISPLAY INVISIBLE (-825 2950);
FORCEPROP 1 LAST HDL_TAP TRUE
J 2
(-1150 2775);
DISPLAY 0.872340 (-1150 2775);
DISPLAY INVISIBLE (-1150 2775);
FORCEPROP 1 LAST PATH I76
J 2
(-823 2900);
DISPLAY 0.872340 (-823 2900);
PAINT GREEN (-823 2900);
DISPLAY INVISIBLE (-823 2900);
FORCEADD TAP..1
R 2
(-825 2950);
FORCEPROP 3 LASTPIN (-775 2950) SIG_NAME M_D_CPU1_SA_DQ<18>
J 0
(-765 2960);
DISPLAY 0.659574 (-765 2960);
PAINT MONO (-765 2960);
DISPLAY INVISIBLE (-765 2960);
FORCEPROP 1 LASTPIN (-775 2950) BN 18
J 2
(-763 2958);
DISPLAY 0.680851 (-763 2958);
PAINT GREEN (-763 2958);
FORCEPROP 2 LAST CDS_LIB standard
J 0
(-825 2950);
DISPLAY INVISIBLE (-825 2950);
FORCEPROP 1 LAST BODY_TYPE PLUMBING
J 2
(-825 3000);
DISPLAY 0.872340 (-825 3000);
PAINT GREEN (-825 3000);
DISPLAY INVISIBLE (-825 3000);
FORCEPROP 1 LAST HDL_TAP TRUE
J 2
(-1150 2825);
DISPLAY 0.872340 (-1150 2825);
DISPLAY INVISIBLE (-1150 2825);
FORCEPROP 1 LAST PATH I77
J 2
(-823 2950);
DISPLAY 0.872340 (-823 2950);
PAINT GREEN (-823 2950);
DISPLAY INVISIBLE (-823 2950);
FORCEADD TAP..1
R 2
(-825 3000);
FORCEPROP 3 LASTPIN (-775 3000) SIG_NAME M_D_CPU1_SA_DQ<19>
J 0
(-765 3010);
DISPLAY 0.659574 (-765 3010);
PAINT MONO (-765 3010);
DISPLAY INVISIBLE (-765 3010);
FORCEPROP 1 LASTPIN (-775 3000) BN 19
J 2
(-763 3008);
DISPLAY 0.680851 (-763 3008);
PAINT GREEN (-763 3008);
FORCEPROP 2 LAST CDS_LIB standard
J 0
(-825 3000);
DISPLAY INVISIBLE (-825 3000);
FORCEPROP 1 LAST BODY_TYPE PLUMBING
J 2
(-825 3050);
DISPLAY 0.872340 (-825 3050);
PAINT GREEN (-825 3050);
DISPLAY INVISIBLE (-825 3050);
FORCEPROP 1 LAST HDL_TAP TRUE
J 2
(-1150 2875);
DISPLAY 0.872340 (-1150 2875);
DISPLAY INVISIBLE (-1150 2875);
FORCEPROP 1 LAST PATH I78
J 2
(-823 3000);
DISPLAY 0.872340 (-823 3000);
PAINT GREEN (-823 3000);
DISPLAY INVISIBLE (-823 3000);
FORCEADD TAP..1
R 2
(-825 3050);
FORCEPROP 3 LASTPIN (-775 3050) SIG_NAME M_D_CPU1_SA_DQ<20>
J 0
(-765 3060);
DISPLAY 0.659574 (-765 3060);
PAINT MONO (-765 3060);
DISPLAY INVISIBLE (-765 3060);
FORCEPROP 1 LASTPIN (-775 3050) BN 20
J 2
(-763 3058);
DISPLAY 0.680851 (-763 3058);
PAINT GREEN (-763 3058);
FORCEPROP 2 LAST CDS_LIB standard
J 0
(-825 3050);
DISPLAY INVISIBLE (-825 3050);
FORCEPROP 1 LAST BODY_TYPE PLUMBING
J 2
(-825 3100);
DISPLAY 0.872340 (-825 3100);
PAINT GREEN (-825 3100);
DISPLAY INVISIBLE (-825 3100);
FORCEPROP 1 LAST HDL_TAP TRUE
J 2
(-1150 2925);
DISPLAY 0.872340 (-1150 2925);
DISPLAY INVISIBLE (-1150 2925);
FORCEPROP 1 LAST PATH I79
J 2
(-823 3050);
DISPLAY 0.872340 (-823 3050);
PAINT GREEN (-823 3050);
DISPLAY INVISIBLE (-823 3050);
FORCEADD TAP..1
R 2
(-825 -300);
FORCEPROP 3 LASTPIN (-775 -300) SIG_NAME M_D_CPU1_SB_CB<1>
J 0
(-765 -290);
DISPLAY 0.659574 (-765 -290);
PAINT MONO (-765 -290);
DISPLAY INVISIBLE (-765 -290);
FORCEPROP 1 LASTPIN (-775 -300) BN 1
J 2
(-763 -292);
DISPLAY 0.680851 (-763 -292);
PAINT GREEN (-763 -292);
FORCEPROP 2 LAST CDS_LIB standard
J 0
(-825 -300);
DISPLAY INVISIBLE (-825 -300);
FORCEPROP 1 LAST BODY_TYPE PLUMBING
J 2
(-825 -250);
DISPLAY 0.872340 (-825 -250);
PAINT GREEN (-825 -250);
DISPLAY INVISIBLE (-825 -250);
FORCEPROP 1 LAST HDL_TAP TRUE
J 2
(-1150 -425);
DISPLAY 0.872340 (-1150 -425);
DISPLAY INVISIBLE (-1150 -425);
FORCEPROP 1 LAST PATH I8
J 2
(-823 -300);
DISPLAY 0.872340 (-823 -300);
PAINT GREEN (-823 -300);
DISPLAY INVISIBLE (-823 -300);
FORCEADD TAP..1
R 2
(-825 3100);
FORCEPROP 3 LASTPIN (-775 3100) SIG_NAME M_D_CPU1_SA_DQ<21>
J 0
(-765 3110);
DISPLAY 0.659574 (-765 3110);
PAINT MONO (-765 3110);
DISPLAY INVISIBLE (-765 3110);
FORCEPROP 1 LASTPIN (-775 3100) BN 21
J 2
(-763 3108);
DISPLAY 0.680851 (-763 3108);
PAINT GREEN (-763 3108);
FORCEPROP 2 LAST CDS_LIB standard
J 0
(-825 3100);
DISPLAY INVISIBLE (-825 3100);
FORCEPROP 1 LAST BODY_TYPE PLUMBING
J 2
(-825 3150);
DISPLAY 0.872340 (-825 3150);
PAINT GREEN (-825 3150);
DISPLAY INVISIBLE (-825 3150);
FORCEPROP 1 LAST HDL_TAP TRUE
J 2
(-1150 2975);
DISPLAY 0.872340 (-1150 2975);
DISPLAY INVISIBLE (-1150 2975);
FORCEPROP 1 LAST PATH I80
J 2
(-823 3100);
DISPLAY 0.872340 (-823 3100);
PAINT GREEN (-823 3100);
DISPLAY INVISIBLE (-823 3100);
FORCEADD TAP..1
R 2
(-825 3150);
FORCEPROP 3 LASTPIN (-775 3150) SIG_NAME M_D_CPU1_SA_DQ<22>
J 0
(-765 3160);
DISPLAY 0.659574 (-765 3160);
PAINT MONO (-765 3160);
DISPLAY INVISIBLE (-765 3160);
FORCEPROP 1 LASTPIN (-775 3150) BN 22
J 2
(-763 3158);
DISPLAY 0.680851 (-763 3158);
PAINT GREEN (-763 3158);
FORCEPROP 2 LAST CDS_LIB standard
J 0
(-825 3150);
DISPLAY INVISIBLE (-825 3150);
FORCEPROP 1 LAST BODY_TYPE PLUMBING
J 2
(-825 3200);
DISPLAY 0.872340 (-825 3200);
PAINT GREEN (-825 3200);
DISPLAY INVISIBLE (-825 3200);
FORCEPROP 1 LAST HDL_TAP TRUE
J 2
(-1150 3025);
DISPLAY 0.872340 (-1150 3025);
DISPLAY INVISIBLE (-1150 3025);
FORCEPROP 1 LAST PATH I81
J 2
(-823 3150);
DISPLAY 0.872340 (-823 3150);
PAINT GREEN (-823 3150);
DISPLAY INVISIBLE (-823 3150);
FORCEADD TAP..1
R 2
(-825 3250);
FORCEPROP 3 LASTPIN (-775 3250) SIG_NAME M_D_CPU1_SA_DQ<24>
J 0
(-765 3260);
DISPLAY 0.659574 (-765 3260);
PAINT MONO (-765 3260);
DISPLAY INVISIBLE (-765 3260);
FORCEPROP 1 LASTPIN (-775 3250) BN 24
J 2
(-763 3258);
DISPLAY 0.680851 (-763 3258);
PAINT GREEN (-763 3258);
FORCEPROP 2 LAST CDS_LIB standard
J 0
(-825 3250);
DISPLAY INVISIBLE (-825 3250);
FORCEPROP 1 LAST BODY_TYPE PLUMBING
J 2
(-825 3300);
DISPLAY 0.872340 (-825 3300);
PAINT GREEN (-825 3300);
DISPLAY INVISIBLE (-825 3300);
FORCEPROP 1 LAST HDL_TAP TRUE
J 2
(-1150 3125);
DISPLAY 0.872340 (-1150 3125);
DISPLAY INVISIBLE (-1150 3125);
FORCEPROP 1 LAST PATH I82
J 2
(-823 3250);
DISPLAY 0.872340 (-823 3250);
PAINT GREEN (-823 3250);
DISPLAY INVISIBLE (-823 3250);
FORCEADD TAP..1
R 2
(-825 3200);
FORCEPROP 3 LASTPIN (-775 3200) SIG_NAME M_D_CPU1_SA_DQ<23>
J 0
(-765 3210);
DISPLAY 0.659574 (-765 3210);
PAINT MONO (-765 3210);
DISPLAY INVISIBLE (-765 3210);
FORCEPROP 1 LASTPIN (-775 3200) BN 23
J 2
(-763 3208);
DISPLAY 0.680851 (-763 3208);
PAINT GREEN (-763 3208);
FORCEPROP 2 LAST CDS_LIB standard
J 0
(-825 3200);
DISPLAY INVISIBLE (-825 3200);
FORCEPROP 1 LAST BODY_TYPE PLUMBING
J 2
(-825 3250);
DISPLAY 0.872340 (-825 3250);
PAINT GREEN (-825 3250);
DISPLAY INVISIBLE (-825 3250);
FORCEPROP 1 LAST HDL_TAP TRUE
J 2
(-1150 3075);
DISPLAY 0.872340 (-1150 3075);
DISPLAY INVISIBLE (-1150 3075);
FORCEPROP 1 LAST PATH I83
J 2
(-823 3200);
DISPLAY 0.872340 (-823 3200);
PAINT GREEN (-823 3200);
DISPLAY INVISIBLE (-823 3200);
FORCEADD TAP..1
R 2
(-825 3300);
FORCEPROP 3 LASTPIN (-775 3300) SIG_NAME M_D_CPU1_SA_DQ<25>
J 0
(-765 3310);
DISPLAY 0.659574 (-765 3310);
PAINT MONO (-765 3310);
DISPLAY INVISIBLE (-765 3310);
FORCEPROP 1 LASTPIN (-775 3300) BN 25
J 2
(-763 3308);
DISPLAY 0.680851 (-763 3308);
PAINT GREEN (-763 3308);
FORCEPROP 2 LAST CDS_LIB standard
J 0
(-825 3300);
DISPLAY INVISIBLE (-825 3300);
FORCEPROP 1 LAST BODY_TYPE PLUMBING
J 2
(-825 3350);
DISPLAY 0.872340 (-825 3350);
PAINT GREEN (-825 3350);
DISPLAY INVISIBLE (-825 3350);
FORCEPROP 1 LAST HDL_TAP TRUE
J 2
(-1150 3175);
DISPLAY 0.872340 (-1150 3175);
DISPLAY INVISIBLE (-1150 3175);
FORCEPROP 1 LAST PATH I84
J 2
(-823 3300);
DISPLAY 0.872340 (-823 3300);
PAINT GREEN (-823 3300);
DISPLAY INVISIBLE (-823 3300);
FORCEADD TAP..1
R 2
(-825 3350);
FORCEPROP 3 LASTPIN (-775 3350) SIG_NAME M_D_CPU1_SA_DQ<26>
J 0
(-765 3360);
DISPLAY 0.659574 (-765 3360);
PAINT MONO (-765 3360);
DISPLAY INVISIBLE (-765 3360);
FORCEPROP 1 LASTPIN (-775 3350) BN 26
J 2
(-763 3358);
DISPLAY 0.680851 (-763 3358);
PAINT GREEN (-763 3358);
FORCEPROP 2 LAST CDS_LIB standard
J 0
(-825 3350);
DISPLAY INVISIBLE (-825 3350);
FORCEPROP 1 LAST BODY_TYPE PLUMBING
J 2
(-825 3400);
DISPLAY 0.872340 (-825 3400);
PAINT GREEN (-825 3400);
DISPLAY INVISIBLE (-825 3400);
FORCEPROP 1 LAST HDL_TAP TRUE
J 2
(-1150 3225);
DISPLAY 0.872340 (-1150 3225);
DISPLAY INVISIBLE (-1150 3225);
FORCEPROP 1 LAST PATH I85
J 2
(-823 3350);
DISPLAY 0.872340 (-823 3350);
PAINT GREEN (-823 3350);
DISPLAY INVISIBLE (-823 3350);
FORCEADD TAP..1
R 2
(-825 3400);
FORCEPROP 3 LASTPIN (-775 3400) SIG_NAME M_D_CPU1_SA_DQ<27>
J 0
(-765 3410);
DISPLAY 0.659574 (-765 3410);
PAINT MONO (-765 3410);
DISPLAY INVISIBLE (-765 3410);
FORCEPROP 1 LASTPIN (-775 3400) BN 27
J 2
(-763 3408);
DISPLAY 0.680851 (-763 3408);
PAINT GREEN (-763 3408);
FORCEPROP 2 LAST CDS_LIB standard
J 0
(-825 3400);
DISPLAY INVISIBLE (-825 3400);
FORCEPROP 1 LAST BODY_TYPE PLUMBING
J 2
(-825 3450);
DISPLAY 0.872340 (-825 3450);
PAINT GREEN (-825 3450);
DISPLAY INVISIBLE (-825 3450);
FORCEPROP 1 LAST HDL_TAP TRUE
J 2
(-1150 3275);
DISPLAY 0.872340 (-1150 3275);
DISPLAY INVISIBLE (-1150 3275);
FORCEPROP 1 LAST PATH I86
J 2
(-823 3400);
DISPLAY 0.872340 (-823 3400);
PAINT GREEN (-823 3400);
DISPLAY INVISIBLE (-823 3400);
FORCEADD TAP..1
R 2
(-825 3450);
FORCEPROP 3 LASTPIN (-775 3450) SIG_NAME M_D_CPU1_SA_DQ<28>
J 0
(-765 3460);
DISPLAY 0.659574 (-765 3460);
PAINT MONO (-765 3460);
DISPLAY INVISIBLE (-765 3460);
FORCEPROP 1 LASTPIN (-775 3450) BN 28
J 2
(-763 3458);
DISPLAY 0.680851 (-763 3458);
PAINT GREEN (-763 3458);
FORCEPROP 2 LAST CDS_LIB standard
J 0
(-825 3450);
DISPLAY INVISIBLE (-825 3450);
FORCEPROP 1 LAST BODY_TYPE PLUMBING
J 2
(-825 3500);
DISPLAY 0.872340 (-825 3500);
PAINT GREEN (-825 3500);
DISPLAY INVISIBLE (-825 3500);
FORCEPROP 1 LAST HDL_TAP TRUE
J 2
(-1150 3325);
DISPLAY 0.872340 (-1150 3325);
DISPLAY INVISIBLE (-1150 3325);
FORCEPROP 1 LAST PATH I87
J 2
(-823 3450);
DISPLAY 0.872340 (-823 3450);
PAINT GREEN (-823 3450);
DISPLAY INVISIBLE (-823 3450);
FORCEADD TAP..1
R 2
(-825 3500);
FORCEPROP 3 LASTPIN (-775 3500) SIG_NAME M_D_CPU1_SA_DQ<29>
J 0
(-765 3510);
DISPLAY 0.659574 (-765 3510);
PAINT MONO (-765 3510);
DISPLAY INVISIBLE (-765 3510);
FORCEPROP 1 LASTPIN (-775 3500) BN 29
J 2
(-763 3508);
DISPLAY 0.680851 (-763 3508);
PAINT GREEN (-763 3508);
FORCEPROP 2 LAST CDS_LIB standard
J 0
(-825 3500);
DISPLAY INVISIBLE (-825 3500);
FORCEPROP 1 LAST BODY_TYPE PLUMBING
J 2
(-825 3550);
DISPLAY 0.872340 (-825 3550);
PAINT GREEN (-825 3550);
DISPLAY INVISIBLE (-825 3550);
FORCEPROP 1 LAST HDL_TAP TRUE
J 2
(-1150 3375);
DISPLAY 0.872340 (-1150 3375);
DISPLAY INVISIBLE (-1150 3375);
FORCEPROP 1 LAST PATH I88
J 2
(-823 3500);
DISPLAY 0.872340 (-823 3500);
PAINT GREEN (-823 3500);
DISPLAY INVISIBLE (-823 3500);
FORCEADD TAP..1
R 2
(-825 3550);
FORCEPROP 3 LASTPIN (-775 3550) SIG_NAME M_D_CPU1_SA_DQ<30>
J 0
(-765 3560);
DISPLAY 0.659574 (-765 3560);
PAINT MONO (-765 3560);
DISPLAY INVISIBLE (-765 3560);
FORCEPROP 1 LASTPIN (-775 3550) BN 30
J 2
(-763 3558);
DISPLAY 0.680851 (-763 3558);
PAINT GREEN (-763 3558);
FORCEPROP 2 LAST CDS_LIB standard
J 0
(-825 3550);
DISPLAY INVISIBLE (-825 3550);
FORCEPROP 1 LAST BODY_TYPE PLUMBING
J 2
(-825 3600);
DISPLAY 0.872340 (-825 3600);
PAINT GREEN (-825 3600);
DISPLAY INVISIBLE (-825 3600);
FORCEPROP 1 LAST HDL_TAP TRUE
J 2
(-1150 3425);
DISPLAY 0.872340 (-1150 3425);
DISPLAY INVISIBLE (-1150 3425);
FORCEPROP 1 LAST PATH I89
J 2
(-823 3550);
DISPLAY 0.872340 (-823 3550);
PAINT GREEN (-823 3550);
DISPLAY INVISIBLE (-823 3550);
FORCEADD OFFPAGE..3
R 2
(-1850 25);
FORCEPROP 2 LAST $XR1 105 
J 0
(-2280 25);
DISPLAY 0.638298 (-2280 25);
PAINT MONO (-2280 25);
FORCEPROP 2 LAST $XR0 104 
J 0
(-2160 25);
DISPLAY 0.638298 (-2160 25);
PAINT MONO (-2160 25);
FORCEPROP 2 LAST CDS_LIB standard
J 0
(-1850 25);
DISPLAY INVISIBLE (-1850 25);
FORCEPROP 1 LAST OFFPAGE TRUE
J 2
(-2175 -100);
DISPLAY 0.872340 (-2175 -100);
DISPLAY INVISIBLE (-2175 -100);
FORCEPROP 1 LAST COMMENT_BODY TRUE
J 2
(-1800 -75);
DISPLAY 0.872340 (-1800 -75);
PAINT GREEN (-1800 -75);
DISPLAY INVISIBLE (-1800 -75);
FORCEPROP 2 LAST PATH I9
J 0
(-1800 100);
DISPLAY 1.021277 (-1800 100);
DISPLAY INVISIBLE (-1800 100);
FORCEADD TAP..1
R 2
(-825 3600);
FORCEPROP 3 LASTPIN (-775 3600) SIG_NAME M_D_CPU1_SA_DQ<31>
J 0
(-765 3610);
DISPLAY 0.659574 (-765 3610);
PAINT MONO (-765 3610);
DISPLAY INVISIBLE (-765 3610);
FORCEPROP 1 LASTPIN (-775 3600) BN 31
J 2
(-763 3608);
DISPLAY 0.680851 (-763 3608);
PAINT GREEN (-763 3608);
FORCEPROP 2 LAST CDS_LIB standard
J 0
(-825 3600);
DISPLAY INVISIBLE (-825 3600);
FORCEPROP 1 LAST BODY_TYPE PLUMBING
J 2
(-825 3650);
DISPLAY 0.872340 (-825 3650);
PAINT GREEN (-825 3650);
DISPLAY INVISIBLE (-825 3650);
FORCEPROP 1 LAST HDL_TAP TRUE
J 2
(-1150 3475);
DISPLAY 0.872340 (-1150 3475);
DISPLAY INVISIBLE (-1150 3475);
FORCEPROP 1 LAST PATH I90
J 2
(-823 3600);
DISPLAY 0.872340 (-823 3600);
PAINT GREEN (-823 3600);
DISPLAY INVISIBLE (-823 3600);
FORCEADD SOCKET4677_AZIF0045P001C01CS..11
(900 1500);
FORCEPROP 1 LAST PART_NUMBER DGA^7000023
J 0
(-200 3850);
DISPLAY 0.723404 (-200 3850);
PAINT GREEN (-200 3850);
DISPLAY INVISIBLE (-200 3850);
FORCEPROP 2 LAST PART_TYPE SMLF
J 0
(-200 4025);
DISPLAY 1.021277 (-200 4025);
FORCEPROP 1 LAST MATERIAL IO
J 0
(-200 3775);
DISPLAY 0.723404 (-200 3775);
PAINT GREEN (-200 3775);
FORCEPROP 2 LAST VALUE SOCKET4677_AZIF0045-P001C01CS
J 0
(-200 3975);
DISPLAY 1.021277 (-200 3975);
FORCEPROP 1 LAST $LOCATION U1
J 0
(-200 3925);
DISPLAY 0.723404 (-200 3925);
PAINT GREEN (-200 3925);
FORCEPROP 0 LASTPIN (2125 -350) $PN AD51
J 0
(2135 -340);
DISPLAY 0.680851 (2135 -340);
PAINT MONO (2135 -340);
FORCEPROP 0 LASTPIN (2125 -300) $PN AC50
J 0
(2135 -290);
DISPLAY 0.680851 (2135 -290);
PAINT MONO (2135 -290);
FORCEPROP 0 LASTPIN (2125 -600) $PN AV47
J 0
(2135 -590);
DISPLAY 0.680851 (2135 -590);
PAINT MONO (2135 -590);
FORCEPROP 0 LASTPIN (2125 -500) $PN AF51
J 0
(2135 -490);
DISPLAY 0.680851 (2135 -490);
PAINT MONO (2135 -490);
FORCEPROP 0 LASTPIN (2125 -450) $PN AG50
J 0
(2135 -440);
DISPLAY 0.680851 (2135 -440);
PAINT MONO (2135 -440);
FORCEPROP 0 LASTPIN (-325 -600) $PN AJ45
J 2
(-335 -590);
DISPLAY 0.680851 (-335 -590);
PAINT MONO (-335 -590);
FORCEPROP 0 LASTPIN (-325 -550) $PN AN45
J 2
(-335 -540);
DISPLAY 0.680851 (-335 -540);
PAINT MONO (-335 -540);
FORCEPROP 0 LASTPIN (-325 -500) $PN AL45
J 2
(-335 -490);
DISPLAY 0.680851 (-335 -490);
PAINT MONO (-335 -490);
FORCEPROP 0 LASTPIN (-325 -450) $PN AR45
J 2
(-335 -440);
DISPLAY 0.680851 (-335 -440);
PAINT MONO (-335 -440);
FORCEPROP 0 LASTPIN (2125 1000) $PN AJ52
J 0
(2135 1010);
DISPLAY 0.680851 (2135 1010);
PAINT MONO (2135 1010);
FORCEPROP 0 LASTPIN (2125 1050) $PN AR52
J 0
(2135 1060);
DISPLAY 0.680851 (2135 1060);
PAINT MONO (2135 1060);
FORCEPROP 0 LASTPIN (2125 1100) $PN AK51
J 0
(2135 1110);
DISPLAY 0.680851 (2135 1110);
PAINT MONO (2135 1110);
FORCEPROP 0 LASTPIN (2125 1150) $PN AP51
J 0
(2135 1160);
DISPLAY 0.680851 (2135 1160);
PAINT MONO (2135 1160);
FORCEPROP 0 LASTPIN (2125 1200) $PN AL50
J 0
(2135 1210);
DISPLAY 0.680851 (2135 1210);
PAINT MONO (2135 1210);
FORCEPROP 0 LASTPIN (2125 1250) $PN AN50
J 0
(2135 1260);
DISPLAY 0.680851 (2135 1260);
PAINT MONO (2135 1260);
FORCEPROP 0 LASTPIN (2125 1300) $PN AN43
J 0
(2135 1310);
DISPLAY 0.680851 (2135 1310);
PAINT MONO (2135 1310);
FORCEPROP 0 LASTPIN (-325 2050) $PN AD75
J 2
(-335 2060);
DISPLAY 0.680851 (-335 2060);
PAINT MONO (-335 2060);
FORCEPROP 0 LASTPIN (-325 2100) $PN AC74
J 2
(-335 2110);
DISPLAY 0.680851 (-335 2110);
PAINT MONO (-335 2110);
FORCEPROP 0 LASTPIN (-325 2150) $PN AF75
J 2
(-335 2160);
DISPLAY 0.680851 (-335 2160);
PAINT MONO (-335 2160);
FORCEPROP 0 LASTPIN (-325 2200) $PN AG74
J 2
(-335 2210);
DISPLAY 0.680851 (-335 2210);
PAINT MONO (-335 2210);
FORCEPROP 0 LASTPIN (-325 2250) $PN AC72
J 2
(-335 2260);
DISPLAY 0.680851 (-335 2260);
PAINT MONO (-335 2260);
FORCEPROP 0 LASTPIN (-325 2300) $PN AD71
J 2
(-335 2310);
DISPLAY 0.680851 (-335 2310);
PAINT MONO (-335 2310);
FORCEPROP 0 LASTPIN (-325 2350) $PN AG72
J 2
(-335 2360);
DISPLAY 0.680851 (-335 2360);
PAINT MONO (-335 2360);
FORCEPROP 0 LASTPIN (-325 2400) $PN AF71
J 2
(-335 2410);
DISPLAY 0.680851 (-335 2410);
PAINT MONO (-335 2410);
FORCEPROP 0 LASTPIN (-325 2450) $PN AL78
J 2
(-335 2460);
DISPLAY 0.680851 (-335 2460);
PAINT MONO (-335 2460);
FORCEPROP 0 LASTPIN (-325 2500) $PN AK77
J 2
(-335 2510);
DISPLAY 0.680851 (-335 2510);
PAINT MONO (-335 2510);
FORCEPROP 0 LASTPIN (-325 2550) $PN AN78
J 2
(-335 2560);
DISPLAY 0.680851 (-335 2560);
PAINT MONO (-335 2560);
FORCEPROP 0 LASTPIN (-325 2600) $PN AP77
J 2
(-335 2610);
DISPLAY 0.680851 (-335 2610);
PAINT MONO (-335 2610);
FORCEPROP 0 LASTPIN (-325 2650) $PN AK75
J 2
(-335 2660);
DISPLAY 0.680851 (-335 2660);
PAINT MONO (-335 2660);
FORCEPROP 0 LASTPIN (-325 2700) $PN AL74
J 2
(-335 2710);
DISPLAY 0.680851 (-335 2710);
PAINT MONO (-335 2710);
FORCEPROP 0 LASTPIN (-325 2750) $PN AP75
J 2
(-335 2760);
DISPLAY 0.680851 (-335 2760);
PAINT MONO (-335 2760);
FORCEPROP 0 LASTPIN (-325 2800) $PN AN74
J 2
(-335 2810);
DISPLAY 0.680851 (-335 2810);
PAINT MONO (-335 2810);
FORCEPROP 0 LASTPIN (-325 2850) $PN AL72
J 2
(-335 2860);
DISPLAY 0.680851 (-335 2860);
PAINT MONO (-335 2860);
FORCEPROP 0 LASTPIN (-325 2900) $PN AK71
J 2
(-335 2910);
DISPLAY 0.680851 (-335 2910);
PAINT MONO (-335 2910);
FORCEPROP 0 LASTPIN (-325 2950) $PN AN72
J 2
(-335 2960);
DISPLAY 0.680851 (-335 2960);
PAINT MONO (-335 2960);
FORCEPROP 0 LASTPIN (-325 3000) $PN AP71
J 2
(-335 3010);
DISPLAY 0.680851 (-335 3010);
PAINT MONO (-335 3010);
FORCEPROP 0 LASTPIN (-325 3050) $PN AK69
J 2
(-335 3060);
DISPLAY 0.680851 (-335 3060);
PAINT MONO (-335 3060);
FORCEPROP 0 LASTPIN (-325 3100) $PN AL68
J 2
(-335 3110);
DISPLAY 0.680851 (-335 3110);
PAINT MONO (-335 3110);
FORCEPROP 0 LASTPIN (-325 3150) $PN AP69
J 2
(-335 3160);
DISPLAY 0.680851 (-335 3160);
PAINT MONO (-335 3160);
FORCEPROP 0 LASTPIN (-325 3200) $PN AN68
J 2
(-335 3210);
DISPLAY 0.680851 (-335 3210);
PAINT MONO (-335 3210);
FORCEPROP 0 LASTPIN (-325 3250) $PN AL66
J 2
(-335 3260);
DISPLAY 0.680851 (-335 3260);
PAINT MONO (-335 3260);
FORCEPROP 0 LASTPIN (-325 3300) $PN AK65
J 2
(-335 3310);
DISPLAY 0.680851 (-335 3310);
PAINT MONO (-335 3310);
FORCEPROP 0 LASTPIN (-325 3350) $PN AN66
J 2
(-335 3360);
DISPLAY 0.680851 (-335 3360);
PAINT MONO (-335 3360);
FORCEPROP 0 LASTPIN (-325 3400) $PN AP65
J 2
(-335 3410);
DISPLAY 0.680851 (-335 3410);
PAINT MONO (-335 3410);
FORCEPROP 0 LASTPIN (-325 3450) $PN AK63
J 2
(-335 3460);
DISPLAY 0.680851 (-335 3460);
PAINT MONO (-335 3460);
FORCEPROP 0 LASTPIN (-325 3500) $PN AL62
J 2
(-335 3510);
DISPLAY 0.680851 (-335 3510);
PAINT MONO (-335 3510);
FORCEPROP 0 LASTPIN (-325 3550) $PN AP63
J 2
(-335 3560);
DISPLAY 0.680851 (-335 3560);
PAINT MONO (-335 3560);
FORCEPROP 0 LASTPIN (-325 3600) $PN AN62
J 2
(-335 3610);
DISPLAY 0.680851 (-335 3610);
PAINT MONO (-335 3610);
FORCEPROP 0 LASTPIN (2125 2600) $PN AB73
J 0
(2135 2610);
DISPLAY 0.680851 (2135 2610);
PAINT MONO (2135 2610);
FORCEPROP 0 LASTPIN (2125 2650) $PN AJ76
J 0
(2135 2660);
DISPLAY 0.680851 (2135 2660);
PAINT MONO (2135 2660);
FORCEPROP 0 LASTPIN (2125 2700) $PN AJ70
J 0
(2135 2710);
DISPLAY 0.680851 (2135 2710);
PAINT MONO (2135 2710);
FORCEPROP 0 LASTPIN (2125 2750) $PN AJ64
J 0
(2135 2760);
DISPLAY 0.680851 (2135 2760);
PAINT MONO (2135 2760);
FORCEPROP 0 LASTPIN (2125 2800) $PN AJ58
J 0
(2135 2810);
DISPLAY 0.680851 (2135 2810);
PAINT MONO (2135 2810);
FORCEPROP 0 LASTPIN (2125 2850) $PN AH73
J 0
(2135 2860);
DISPLAY 0.680851 (2135 2860);
PAINT MONO (2135 2860);
FORCEPROP 0 LASTPIN (2125 2900) $PN AN76
J 0
(2135 2910);
DISPLAY 0.680851 (2135 2910);
PAINT MONO (2135 2910);
FORCEPROP 0 LASTPIN (2125 2950) $PN AN70
J 0
(2135 2960);
DISPLAY 0.680851 (2135 2960);
PAINT MONO (2135 2960);
FORCEPROP 0 LASTPIN (2125 3000) $PN AN64
J 0
(2135 3010);
DISPLAY 0.680851 (2135 3010);
PAINT MONO (2135 3010);
FORCEPROP 0 LASTPIN (2125 3050) $PN AN58
J 0
(2135 3060);
DISPLAY 0.680851 (2135 3060);
PAINT MONO (2135 3060);
FORCEPROP 0 LASTPIN (2125 3150) $PN AD73
J 0
(2135 3160);
DISPLAY 0.680851 (2135 3160);
PAINT MONO (2135 3160);
FORCEPROP 0 LASTPIN (2125 3200) $PN AL76
J 0
(2135 3210);
DISPLAY 0.680851 (2135 3210);
PAINT MONO (2135 3210);
FORCEPROP 0 LASTPIN (2125 3250) $PN AL70
J 0
(2135 3260);
DISPLAY 0.680851 (2135 3260);
PAINT MONO (2135 3260);
FORCEPROP 0 LASTPIN (2125 3300) $PN AL64
J 0
(2135 3310);
DISPLAY 0.680851 (2135 3310);
PAINT MONO (2135 3310);
FORCEPROP 0 LASTPIN (2125 3350) $PN AL58
J 0
(2135 3360);
DISPLAY 0.680851 (2135 3360);
PAINT MONO (2135 3360);
FORCEPROP 0 LASTPIN (2125 3400) $PN AF73
J 0
(2135 3410);
DISPLAY 0.680851 (2135 3410);
PAINT MONO (2135 3410);
FORCEPROP 0 LASTPIN (2125 3450) $PN AR76
J 0
(2135 3460);
DISPLAY 0.680851 (2135 3460);
PAINT MONO (2135 3460);
FORCEPROP 0 LASTPIN (2125 3500) $PN AR70
J 0
(2135 3510);
DISPLAY 0.680851 (2135 3510);
PAINT MONO (2135 3510);
FORCEPROP 0 LASTPIN (2125 3550) $PN AR64
J 0
(2135 3560);
DISPLAY 0.680851 (2135 3560);
PAINT MONO (2135 3560);
FORCEPROP 0 LASTPIN (2125 3600) $PN AR58
J 0
(2135 3610);
DISPLAY 0.680851 (2135 3610);
PAINT MONO (2135 3610);
FORCEPROP 0 LASTPIN (-325 1650) $PN AL60
J 2
(-335 1660);
DISPLAY 0.680851 (-335 1660);
PAINT MONO (-335 1660);
FORCEPROP 0 LASTPIN (-325 1700) $PN AK59
J 2
(-335 1710);
DISPLAY 0.680851 (-335 1710);
PAINT MONO (-335 1710);
FORCEPROP 0 LASTPIN (-325 1750) $PN AN60
J 2
(-335 1760);
DISPLAY 0.680851 (-335 1760);
PAINT MONO (-335 1760);
FORCEPROP 0 LASTPIN (-325 1800) $PN AP59
J 2
(-335 1810);
DISPLAY 0.680851 (-335 1810);
PAINT MONO (-335 1810);
FORCEPROP 0 LASTPIN (-325 1850) $PN AK57
J 2
(-335 1860);
DISPLAY 0.680851 (-335 1860);
PAINT MONO (-335 1860);
FORCEPROP 0 LASTPIN (-325 1900) $PN AL56
J 2
(-335 1910);
DISPLAY 0.680851 (-335 1910);
PAINT MONO (-335 1910);
FORCEPROP 0 LASTPIN (-325 1950) $PN AP57
J 2
(-335 1960);
DISPLAY 0.680851 (-335 1960);
PAINT MONO (-335 1960);
FORCEPROP 0 LASTPIN (-325 2000) $PN AN56
J 2
(-335 2010);
DISPLAY 0.680851 (-335 2010);
PAINT MONO (-335 2010);
FORCEPROP 0 LASTPIN (2125 950) $PN AP44
J 0
(2135 960);
DISPLAY 0.680851 (2135 960);
PAINT MONO (2135 960);
FORCEPROP 0 LASTPIN (2125 500) $PN AK44
J 0
(2135 510);
DISPLAY 0.680851 (2135 510);
PAINT MONO (2135 510);
FORCEPROP 0 LASTPIN (2125 550) $PN AL43
J 0
(2135 560);
DISPLAY 0.680851 (2135 560);
PAINT MONO (2135 560);
FORCEPROP 0 LASTPIN (2125 600) $PN AD44
J 0
(2135 610);
DISPLAY 0.680851 (2135 610);
PAINT MONO (2135 610);
FORCEPROP 0 LASTPIN (2125 650) $PN AF44
J 0
(2135 660);
DISPLAY 0.680851 (2135 660);
PAINT MONO (2135 660);
FORCEPROP 0 LASTPIN (2125 700) $PN AC43
J 0
(2135 710);
DISPLAY 0.680851 (2135 710);
PAINT MONO (2135 710);
FORCEPROP 0 LASTPIN (2125 750) $PN AG43
J 0
(2135 760);
DISPLAY 0.680851 (2135 760);
PAINT MONO (2135 760);
FORCEPROP 0 LASTPIN (2125 800) $PN AB42
J 0
(2135 810);
DISPLAY 0.680851 (2135 810);
PAINT MONO (2135 810);
FORCEPROP 0 LASTPIN (-325 50) $PN AL35
J 2
(-335 60);
DISPLAY 0.680851 (-335 60);
PAINT MONO (-335 60);
FORCEPROP 0 LASTPIN (-325 100) $PN AK34
J 2
(-335 110);
DISPLAY 0.680851 (-335 110);
PAINT MONO (-335 110);
FORCEPROP 0 LASTPIN (-325 150) $PN AN35
J 2
(-335 160);
DISPLAY 0.680851 (-335 160);
PAINT MONO (-335 160);
FORCEPROP 0 LASTPIN (-325 200) $PN AP34
J 2
(-335 210);
DISPLAY 0.680851 (-335 210);
PAINT MONO (-335 210);
FORCEPROP 0 LASTPIN (-325 250) $PN AK32
J 2
(-335 260);
DISPLAY 0.680851 (-335 260);
PAINT MONO (-335 260);
FORCEPROP 0 LASTPIN (-325 300) $PN AL31
J 2
(-335 310);
DISPLAY 0.680851 (-335 310);
PAINT MONO (-335 310);
FORCEPROP 0 LASTPIN (-325 350) $PN AP32
J 2
(-335 360);
DISPLAY 0.680851 (-335 360);
PAINT MONO (-335 360);
FORCEPROP 0 LASTPIN (-325 400) $PN AN31
J 2
(-335 410);
DISPLAY 0.680851 (-335 410);
PAINT MONO (-335 410);
FORCEPROP 0 LASTPIN (-325 450) $PN AL29
J 2
(-335 460);
DISPLAY 0.680851 (-335 460);
PAINT MONO (-335 460);
FORCEPROP 0 LASTPIN (-325 500) $PN AK28
J 2
(-335 510);
DISPLAY 0.680851 (-335 510);
PAINT MONO (-335 510);
FORCEPROP 0 LASTPIN (-325 550) $PN AN29
J 2
(-335 560);
DISPLAY 0.680851 (-335 560);
PAINT MONO (-335 560);
FORCEPROP 0 LASTPIN (-325 600) $PN AP28
J 2
(-335 610);
DISPLAY 0.680851 (-335 610);
PAINT MONO (-335 610);
FORCEPROP 0 LASTPIN (-325 650) $PN AK26
J 2
(-335 660);
DISPLAY 0.680851 (-335 660);
PAINT MONO (-335 660);
FORCEPROP 0 LASTPIN (-325 700) $PN AL25
J 2
(-335 710);
DISPLAY 0.680851 (-335 710);
PAINT MONO (-335 710);
FORCEPROP 0 LASTPIN (-325 750) $PN AP26
J 2
(-335 760);
DISPLAY 0.680851 (-335 760);
PAINT MONO (-335 760);
FORCEPROP 0 LASTPIN (-325 800) $PN AN25
J 2
(-335 810);
DISPLAY 0.680851 (-335 810);
PAINT MONO (-335 810);
FORCEPROP 0 LASTPIN (-325 850) $PN AD26
J 2
(-335 860);
DISPLAY 0.680851 (-335 860);
PAINT MONO (-335 860);
FORCEPROP 0 LASTPIN (-325 900) $PN AC25
J 2
(-335 910);
DISPLAY 0.680851 (-335 910);
PAINT MONO (-335 910);
FORCEPROP 0 LASTPIN (-325 950) $PN AF26
J 2
(-335 960);
DISPLAY 0.680851 (-335 960);
PAINT MONO (-335 960);
FORCEPROP 0 LASTPIN (-325 1000) $PN AG25
J 2
(-335 1010);
DISPLAY 0.680851 (-335 1010);
PAINT MONO (-335 1010);
FORCEPROP 0 LASTPIN (-325 1050) $PN AC23
J 2
(-335 1060);
DISPLAY 0.680851 (-335 1060);
PAINT MONO (-335 1060);
FORCEPROP 0 LASTPIN (-325 1100) $PN AD22
J 2
(-335 1110);
DISPLAY 0.680851 (-335 1110);
PAINT MONO (-335 1110);
FORCEPROP 0 LASTPIN (-325 1150) $PN AG23
J 2
(-335 1160);
DISPLAY 0.680851 (-335 1160);
PAINT MONO (-335 1160);
FORCEPROP 0 LASTPIN (-325 1200) $PN AF22
J 2
(-335 1210);
DISPLAY 0.680851 (-335 1210);
PAINT MONO (-335 1210);
FORCEPROP 0 LASTPIN (-325 1250) $PN AL23
J 2
(-335 1260);
DISPLAY 0.680851 (-335 1260);
PAINT MONO (-335 1260);
FORCEPROP 0 LASTPIN (-325 1300) $PN AK22
J 2
(-335 1310);
DISPLAY 0.680851 (-335 1310);
PAINT MONO (-335 1310);
FORCEPROP 0 LASTPIN (-325 1350) $PN AN23
J 2
(-335 1360);
DISPLAY 0.680851 (-335 1360);
PAINT MONO (-335 1360);
FORCEPROP 0 LASTPIN (-325 1400) $PN AP22
J 2
(-335 1410);
DISPLAY 0.680851 (-335 1410);
PAINT MONO (-335 1410);
FORCEPROP 0 LASTPIN (-325 1450) $PN AK20
J 2
(-335 1460);
DISPLAY 0.680851 (-335 1460);
PAINT MONO (-335 1460);
FORCEPROP 0 LASTPIN (-325 1500) $PN AL19
J 2
(-335 1510);
DISPLAY 0.680851 (-335 1510);
PAINT MONO (-335 1510);
FORCEPROP 0 LASTPIN (-325 1550) $PN AP20
J 2
(-335 1560);
DISPLAY 0.680851 (-335 1560);
PAINT MONO (-335 1560);
FORCEPROP 0 LASTPIN (-325 1600) $PN AN19
J 2
(-335 1610);
DISPLAY 0.680851 (-335 1610);
PAINT MONO (-335 1610);
FORCEPROP 0 LASTPIN (2125 1450) $PN AJ33
J 0
(2135 1460);
DISPLAY 0.680851 (2135 1460);
PAINT MONO (2135 1460);
FORCEPROP 0 LASTPIN (2125 1500) $PN AJ27
J 0
(2135 1510);
DISPLAY 0.680851 (2135 1510);
PAINT MONO (2135 1510);
FORCEPROP 0 LASTPIN (2125 1550) $PN AB24
J 0
(2135 1560);
DISPLAY 0.680851 (2135 1560);
PAINT MONO (2135 1560);
FORCEPROP 0 LASTPIN (2125 1600) $PN AJ21
J 0
(2135 1610);
DISPLAY 0.680851 (2135 1610);
PAINT MONO (2135 1610);
FORCEPROP 0 LASTPIN (2125 1650) $PN AR39
J 0
(2135 1660);
DISPLAY 0.680851 (2135 1660);
PAINT MONO (2135 1660);
FORCEPROP 0 LASTPIN (2125 1700) $PN AN33
J 0
(2135 1710);
DISPLAY 0.680851 (2135 1710);
PAINT MONO (2135 1710);
FORCEPROP 0 LASTPIN (2125 1750) $PN AN27
J 0
(2135 1760);
DISPLAY 0.680851 (2135 1760);
PAINT MONO (2135 1760);
FORCEPROP 0 LASTPIN (2125 1800) $PN AF24
J 0
(2135 1810);
DISPLAY 0.680851 (2135 1810);
PAINT MONO (2135 1810);
FORCEPROP 0 LASTPIN (2125 1850) $PN AN21
J 0
(2135 1860);
DISPLAY 0.680851 (2135 1860);
PAINT MONO (2135 1860);
FORCEPROP 0 LASTPIN (2125 1900) $PN AJ39
J 0
(2135 1910);
DISPLAY 0.680851 (2135 1910);
PAINT MONO (2135 1910);
FORCEPROP 0 LASTPIN (2125 2000) $PN AL33
J 0
(2135 2010);
DISPLAY 0.680851 (2135 2010);
PAINT MONO (2135 2010);
FORCEPROP 0 LASTPIN (2125 2050) $PN AL27
J 0
(2135 2060);
DISPLAY 0.680851 (2135 2060);
PAINT MONO (2135 2060);
FORCEPROP 0 LASTPIN (2125 2100) $PN AD24
J 0
(2135 2110);
DISPLAY 0.680851 (2135 2110);
PAINT MONO (2135 2110);
FORCEPROP 0 LASTPIN (2125 2150) $PN AL21
J 0
(2135 2160);
DISPLAY 0.680851 (2135 2160);
PAINT MONO (2135 2160);
FORCEPROP 0 LASTPIN (2125 2200) $PN AN39
J 0
(2135 2210);
DISPLAY 0.680851 (2135 2210);
PAINT MONO (2135 2210);
FORCEPROP 0 LASTPIN (2125 2250) $PN AR33
J 0
(2135 2260);
DISPLAY 0.680851 (2135 2260);
PAINT MONO (2135 2260);
FORCEPROP 0 LASTPIN (2125 2300) $PN AR27
J 0
(2135 2310);
DISPLAY 0.680851 (2135 2310);
PAINT MONO (2135 2310);
FORCEPROP 0 LASTPIN (2125 2350) $PN AH24
J 0
(2135 2360);
DISPLAY 0.680851 (2135 2360);
PAINT MONO (2135 2360);
FORCEPROP 0 LASTPIN (2125 2400) $PN AR21
J 0
(2135 2410);
DISPLAY 0.680851 (2135 2410);
PAINT MONO (2135 2410);
FORCEPROP 0 LASTPIN (2125 2450) $PN AL39
J 0
(2135 2460);
DISPLAY 0.680851 (2135 2460);
PAINT MONO (2135 2460);
FORCEPROP 0 LASTPIN (-325 -350) $PN AK38
J 2
(-335 -340);
DISPLAY 0.680851 (-335 -340);
PAINT MONO (-335 -340);
FORCEPROP 0 LASTPIN (-325 -300) $PN AL37
J 2
(-335 -290);
DISPLAY 0.680851 (-335 -290);
PAINT MONO (-335 -290);
FORCEPROP 0 LASTPIN (-325 -250) $PN AP38
J 2
(-335 -240);
DISPLAY 0.680851 (-335 -240);
PAINT MONO (-335 -240);
FORCEPROP 0 LASTPIN (-325 -200) $PN AN37
J 2
(-335 -190);
DISPLAY 0.680851 (-335 -190);
PAINT MONO (-335 -190);
FORCEPROP 0 LASTPIN (-325 -150) $PN AL41
J 2
(-335 -140);
DISPLAY 0.680851 (-335 -140);
PAINT MONO (-335 -140);
FORCEPROP 0 LASTPIN (-325 -100) $PN AK40
J 2
(-335 -90);
DISPLAY 0.680851 (-335 -90);
PAINT MONO (-335 -90);
FORCEPROP 0 LASTPIN (-325 -50) $PN AN41
J 2
(-335 -40);
DISPLAY 0.680851 (-335 -40);
PAINT MONO (-335 -40);
FORCEPROP 0 LASTPIN (-325 0) $PN AP40
J 2
(-335 10);
DISPLAY 0.680851 (-335 10);
PAINT MONO (-335 10);
FORCEPROP 0 LASTPIN (2125 450) $PN AH42
J 0
(2135 460);
DISPLAY 0.680851 (2135 460);
PAINT MONO (2135 460);
FORCEPROP 0 LASTPIN (2125 150) $PN AL54
J 0
(2135 160);
DISPLAY 0.680851 (2135 160);
PAINT MONO (2135 160);
FORCEPROP 0 LASTPIN (2125 200) $PN AK53
J 0
(2135 210);
DISPLAY 0.680851 (2135 210);
PAINT MONO (2135 210);
FORCEPROP 0 LASTPIN (2125 250) $PN AN54
J 0
(2135 260);
DISPLAY 0.680851 (2135 260);
PAINT MONO (2135 260);
FORCEPROP 0 LASTPIN (2125 300) $PN AP53
J 0
(2135 310);
DISPLAY 0.680851 (2135 310);
PAINT MONO (2135 310);
FORCEPROP 0 LASTPIN (2125 -150) $PN AC41
J 0
(2135 -140);
DISPLAY 0.680851 (2135 -140);
PAINT MONO (2135 -140);
FORCEPROP 0 LASTPIN (2125 -100) $PN AG41
J 0
(2135 -90);
DISPLAY 0.680851 (2135 -90);
PAINT MONO (2135 -90);
FORCEPROP 0 LASTPIN (2125 -50) $PN AF40
J 0
(2135 -40);
DISPLAY 0.680851 (2135 -40);
PAINT MONO (2135 -40);
FORCEPROP 0 LASTPIN (2125 0) $PN AD40
J 0
(2135 10);
DISPLAY 0.680851 (2135 10);
PAINT MONO (2135 10);
FORCEPROP 2 LAST CDS_LIB pure_quanta
J 0
(900 1500);
DISPLAY INVISIBLE (900 1500);
FORCEPROP 1 LAST NEEDS_NO_SIZE TRUE
J 0
(900 1500);
DISPLAY 0.723404 (900 1500);
PAINT GREEN (900 1500);
DISPLAY INVISIBLE (900 1500);
FORCEPROP 1 LAST CDS_LMAN_SYM_OUTLINE -1100,2250,1050,-2250
J 0
(900 1500);
DISPLAY 0.468085 (900 1500);
PAINT GREEN (900 1500);
DISPLAY INVISIBLE (900 1500);
FORCEPROP 2 LAST CDS_LOCATION U1
J 0
(-200 4075);
DISPLAY 1.021277 (-200 4075);
DISPLAY INVISIBLE (-200 4075);
FORCEPROP 0 LAST $SEC 11
J 0
(-200 4075);
DISPLAY 0.680851 (-200 4075);
PAINT MONO (-200 4075);
DISPLAY INVISIBLE (-200 4075);
FORCEPROP 2 LAST CDS_SEC 11
J 0
(-200 4075);
DISPLAY 1.021277 (-200 4075);
DISPLAY INVISIBLE (-200 4075);
FORCEPROP 1 LAST PATH I91
J 0
(900 1500);
DISPLAY 0.723404 (900 1500);
PAINT GREEN (900 1500);
DISPLAY INVISIBLE (900 1500);
FORCEADD OFFPAGE..4
(3700 -600);
FORCEPROP 2 LAST $XR1 105 
J 0
(4006 -600);
DISPLAY 0.638298 (4006 -600);
PAINT MONO (4006 -600);
FORCEPROP 2 LAST $XR0 104 
J 0
(3886 -600);
DISPLAY 0.638298 (3886 -600);
PAINT MONO (3886 -600);
FORCEPROP 2 LAST CDS_LIB standard
J 0
(3700 -600);
PAINT MONO (3700 -600);
DISPLAY INVISIBLE (3700 -600);
FORCEPROP 1 LAST OFFPAGE TRUE
J 0
(4025 -725);
DISPLAY 1.170213 (4025 -725);
PAINT GREEN (4025 -725);
DISPLAY INVISIBLE (4025 -725);
FORCEPROP 1 LAST COMMENT_BODY TRUE
J 0
(3675 -700);
DISPLAY 1.170213 (3675 -700);
PAINT GREEN (3675 -700);
DISPLAY INVISIBLE (3675 -700);
FORCEPROP 2 LAST PATH I92
J 0
(3875 -525);
DISPLAY 1.021277 (3875 -525);
DISPLAY INVISIBLE (3875 -525);
FORCEADD OFFPAGE..4
(3700 -500);
FORCEPROP 2 LAST $XR0 104 
J 0
(3886 -500);
DISPLAY 0.638298 (3886 -500);
PAINT MONO (3886 -500);
FORCEPROP 2 LAST CDS_LIB standard
J 0
(3700 -500);
PAINT MONO (3700 -500);
DISPLAY INVISIBLE (3700 -500);
FORCEPROP 1 LAST OFFPAGE TRUE
J 0
(4025 -625);
DISPLAY 1.170213 (4025 -625);
PAINT GREEN (4025 -625);
DISPLAY INVISIBLE (4025 -625);
FORCEPROP 1 LAST COMMENT_BODY TRUE
J 0
(3675 -600);
DISPLAY 1.170213 (3675 -600);
PAINT GREEN (3675 -600);
DISPLAY INVISIBLE (3675 -600);
FORCEPROP 2 LAST PATH I93
J 0
(3875 -425);
DISPLAY 1.021277 (3875 -425);
DISPLAY INVISIBLE (3875 -425);
FORCEADD OFFPAGE..4
(3700 -450);
FORCEPROP 2 LAST $XR0 105 
J 0
(3886 -450);
DISPLAY 0.638298 (3886 -450);
PAINT MONO (3886 -450);
FORCEPROP 2 LAST CDS_LIB standard
J 0
(3700 -450);
PAINT MONO (3700 -450);
DISPLAY INVISIBLE (3700 -450);
FORCEPROP 1 LAST OFFPAGE TRUE
J 0
(4025 -575);
DISPLAY 1.170213 (4025 -575);
PAINT GREEN (4025 -575);
DISPLAY INVISIBLE (4025 -575);
FORCEPROP 1 LAST COMMENT_BODY TRUE
J 0
(3675 -550);
DISPLAY 1.170213 (3675 -550);
PAINT GREEN (3675 -550);
DISPLAY INVISIBLE (3675 -550);
FORCEPROP 2 LAST PATH I94
J 0
(3875 -375);
DISPLAY 1.021277 (3875 -375);
DISPLAY INVISIBLE (3875 -375);
FORCEADD OFFPAGE..4
(3700 -350);
FORCEPROP 2 LAST $XR0 104 
J 0
(3886 -350);
DISPLAY 0.638298 (3886 -350);
PAINT MONO (3886 -350);
FORCEPROP 2 LAST CDS_LIB standard
J 0
(3700 -350);
PAINT MONO (3700 -350);
DISPLAY INVISIBLE (3700 -350);
FORCEPROP 1 LAST OFFPAGE TRUE
J 0
(4025 -475);
DISPLAY 1.170213 (4025 -475);
PAINT GREEN (4025 -475);
DISPLAY INVISIBLE (4025 -475);
FORCEPROP 1 LAST COMMENT_BODY TRUE
J 0
(3675 -450);
DISPLAY 1.170213 (3675 -450);
PAINT GREEN (3675 -450);
DISPLAY INVISIBLE (3675 -450);
FORCEPROP 2 LAST PATH I95
J 0
(3875 -275);
DISPLAY 1.021277 (3875 -275);
DISPLAY INVISIBLE (3875 -275);
FORCEADD OFFPAGE..4
(3700 -300);
FORCEPROP 2 LAST $XR0 105 
J 0
(3886 -300);
DISPLAY 0.638298 (3886 -300);
PAINT MONO (3886 -300);
FORCEPROP 2 LAST CDS_LIB standard
J 0
(3700 -300);
PAINT MONO (3700 -300);
DISPLAY INVISIBLE (3700 -300);
FORCEPROP 1 LAST OFFPAGE TRUE
J 0
(4025 -425);
DISPLAY 1.170213 (4025 -425);
PAINT GREEN (4025 -425);
DISPLAY INVISIBLE (4025 -425);
FORCEPROP 1 LAST COMMENT_BODY TRUE
J 0
(3675 -400);
DISPLAY 1.170213 (3675 -400);
PAINT GREEN (3675 -400);
DISPLAY INVISIBLE (3675 -400);
FORCEPROP 2 LAST PATH I96
J 0
(3875 -225);
DISPLAY 1.021277 (3875 -225);
DISPLAY INVISIBLE (3875 -225);
FORCEADD TAP..1
(2600 -150);
FORCEPROP 3 LASTPIN (2550 -150) SIG_NAME M_D_CPU1_SB_CS_N<0>
J 0
(2560 -140);
DISPLAY 0.659574 (2560 -140);
PAINT MONO (2560 -140);
DISPLAY INVISIBLE (2560 -140);
FORCEPROP 1 LASTPIN (2550 -150) BN 0
J 0
(2538 -142);
DISPLAY 0.680851 (2538 -142);
PAINT GREEN (2538 -142);
FORCEPROP 2 LAST CDS_LIB standard
J 0
(2600 -150);
DISPLAY INVISIBLE (2600 -150);
FORCEPROP 1 LAST BODY_TYPE PLUMBING
J 0
(2600 -100);
DISPLAY 0.872340 (2600 -100);
PAINT GREEN (2600 -100);
DISPLAY INVISIBLE (2600 -100);
FORCEPROP 1 LAST HDL_TAP TRUE
J 0
(2925 -275);
DISPLAY 0.872340 (2925 -275);
DISPLAY INVISIBLE (2925 -275);
FORCEPROP 1 LAST PATH I97
J 0
(2598 -150);
DISPLAY 0.872340 (2598 -150);
PAINT GREEN (2598 -150);
DISPLAY INVISIBLE (2598 -150);
FORCEADD TAP..1
(2600 -100);
FORCEPROP 3 LASTPIN (2550 -100) SIG_NAME M_D_CPU1_SB_CS_N<1>
J 0
(2560 -90);
DISPLAY 0.659574 (2560 -90);
PAINT MONO (2560 -90);
DISPLAY INVISIBLE (2560 -90);
FORCEPROP 1 LASTPIN (2550 -100) BN 1
J 0
(2538 -92);
DISPLAY 0.680851 (2538 -92);
PAINT GREEN (2538 -92);
FORCEPROP 2 LAST CDS_LIB standard
J 0
(2600 -100);
DISPLAY INVISIBLE (2600 -100);
FORCEPROP 1 LAST BODY_TYPE PLUMBING
J 0
(2600 -50);
DISPLAY 0.872340 (2600 -50);
PAINT GREEN (2600 -50);
DISPLAY INVISIBLE (2600 -50);
FORCEPROP 1 LAST HDL_TAP TRUE
J 0
(2925 -225);
DISPLAY 0.872340 (2925 -225);
DISPLAY INVISIBLE (2925 -225);
FORCEPROP 1 LAST PATH I98
J 0
(2598 -100);
DISPLAY 0.872340 (2598 -100);
PAINT GREEN (2598 -100);
DISPLAY INVISIBLE (2598 -100);
FORCEADD TAP..1
(2600 -50);
FORCEPROP 3 LASTPIN (2550 -50) SIG_NAME M_D_CPU1_SB_CS_N<2>
J 0
(2560 -40);
DISPLAY 0.659574 (2560 -40);
PAINT MONO (2560 -40);
DISPLAY INVISIBLE (2560 -40);
FORCEPROP 1 LASTPIN (2550 -50) BN 2
J 0
(2538 -42);
DISPLAY 0.680851 (2538 -42);
PAINT GREEN (2538 -42);
FORCEPROP 2 LAST CDS_LIB standard
J 0
(2600 -50);
DISPLAY INVISIBLE (2600 -50);
FORCEPROP 1 LAST BODY_TYPE PLUMBING
J 0
(2600 0);
DISPLAY 0.872340 (2600 0);
PAINT GREEN (2600 0);
DISPLAY INVISIBLE (2600 0);
FORCEPROP 1 LAST HDL_TAP TRUE
J 0
(2925 -175);
DISPLAY 0.872340 (2925 -175);
DISPLAY INVISIBLE (2925 -175);
FORCEPROP 1 LAST PATH I99
J 0
(2598 -50);
DISPLAY 0.872340 (2598 -50);
PAINT GREEN (2598 -50);
DISPLAY INVISIBLE (2598 -50);
FORCEADD QUANTA_TITLE_BLOCK_C..1
(5525 -1900);
FORCEPROP 0 LAST CDS_CON_LAST_MODIFIED Fri Aug 25 14:00:36 2023
J 0
(3640 -1885);
PAINT MONO (3640 -1885);
DISPLAY INVISIBLE (3640 -1885);
FORCEPROP 1 LAST CUSTOM_TXT_CDS <CON_LAST_MODIFIED>
J 0
(3640 -1885);
DISPLAY 0.978723 (3640 -1885);
FORCEPROP 2 LAST CUSTOM_TXT_CDS <XR_PAGE_TITLE>
J 0
(-2365 3350);
DISPLAY 0.638298 (-2365 3350);
PAINT PINK (-2365 3350);
DISPLAY INVISIBLE (-2365 3350);
FORCEPROP 2 LAST CUSTOM_TXT_CDS <Q_NUMBER>
J 0
(4122 -1797);
DISPLAY 1.212766 (4122 -1797);
FORCEPROP 1 LAST CUSTOM_TXT_CDS <NAME_2>
J 0
(2350 -1850);
FORCEPROP 1 LAST CUSTOM_TXT_CDS <NAME_1>
J 0
(2350 -1725);
FORCEPROP 1 LAST CUSTOM_TXT_CDS <Q_PROJ>
J 0
(3143 -1798);
DISPLAY 1.212766 (3143 -1798);
FORCEPROP 1 LAST CUSTOM_TXT_CDS <Q_REV>
J 0
(5341 -1797);
DISPLAY 1.212766 (5341 -1797);
FORCEPROP 1 LAST CUSTOM_TXT_CDS <CON_PAGE_NUM> OF <CON_TOTAL_PAGES>
J 0
(5079 -1882);
DISPLAY 0.978723 (5079 -1882);
FORCEPROP 1 LAST Q_TITLE SPR CPU1 - DDR CH D (11 OF 30)
J 0
(-3841 -1874);
DISPLAY 1.957447 (-3841 -1874);
PAINT GREEN (-3841 -1874);
FORCEPROP 1 LAST Q_DEPT 
J 1
(1762 -1851);
DISPLAY 1.957447 (1762 -1851);
PAINT GREEN (1762 -1851);
FORCEPROP 1 LAST COMMENT_BODY TRUE
J 0
(5537 -1913);
DISPLAY 0.978723 (5537 -1913);
PAINT GREEN (5537 -1913);
DISPLAY INVISIBLE (5537 -1913);
FORCEPROP 2 LAST CDS_XR_PAGE_TITLE CR-54 : @S9S_MB_2U_LIB.S9S_MB_2U(SCH_1):PAGE54
J 0
(-2365 3350);
DISPLAY 0.638298 (-2365 3350);
PAINT PINK (-2365 3350);
DISPLAY INVISIBLE (-2365 3350);
FORCEPROP 2 LAST CDS_LIB pure_quanta
J 0
(5525 -1900);
PAINT MONO (5525 -1900);
DISPLAY INVISIBLE (5525 -1900);
FORCEPROP 1 LAST CDS_LMAN_SYM_OUTLINE -9475,6775,100,-125
J 0
(5525 -1900);
DISPLAY 0.468085 (5525 -1900);
PAINT GREEN (5525 -1900);
DISPLAY INVISIBLE (5525 -1900);
FORCEPROP 2 LAST PAGE_BORDER TRUE
J 0
(-2365 3350);
DISPLAY 0.638298 (-2365 3350);
PAINT PINK (-2365 3350);
DISPLAY INVISIBLE (-2365 3350);
WIRE 17 -1 (2650 1325)(3650 1325);
FORCEPROP 2 LAST SIG_NAME M_D_CPU1_SA_CA<6:0>
J 0
(2790 1335);
DISPLAY 0.680851 (2790 1335);
PAINT WHITE (2790 1335);
WIRE 17 -1 (2650 1275)(2650 1325);
WIRE 17 -1 (2650 1225)(2650 1275);
WIRE 17 -1 (2650 1175)(2650 1225);
WIRE 17 -1 (2650 1125)(2650 1175);
WIRE 17 -1 (2650 1075)(2650 1125);
WIRE 17 -1 (2650 1025)(2650 1075);
WIRE 17 -1 (2650 325)(3650 325);
FORCEPROP 2 LAST SIG_NAME M_D_CPU1_SA_CS_N<3:0>
J 0
(2790 335);
DISPLAY 0.680851 (2790 335);
PAINT WHITE (2790 335);
WIRE 17 -1 (2650 275)(2650 325);
WIRE 17 -1 (2650 225)(2650 275);
WIRE 17 -1 (2650 175)(2650 225);
WIRE 17 -1 (2650 3075)(3650 3075);
FORCEPROP 2 LAST SIG_NAME M_D_CPU1_SA_DQS_DN<9:0>
J 0
(2790 3085);
DISPLAY 0.680851 (2790 3085);
PAINT WHITE (2790 3085);
WIRE 17 -1 (2650 3025)(2650 3075);
WIRE 17 -1 (2650 2975)(2650 3025);
WIRE 17 -1 (2650 2925)(2650 2975);
WIRE 17 -1 (2650 2875)(2650 2925);
WIRE 17 -1 (2650 2825)(2650 2875);
WIRE 17 -1 (2650 2775)(2650 2825);
WIRE 17 -1 (2650 2725)(2650 2775);
WIRE 17 -1 (2650 2675)(2650 2725);
WIRE 17 -1 (2650 2625)(2650 2675);
WIRE 17 -1 (2650 3625)(3650 3625);
FORCEPROP 2 LAST SIG_NAME M_D_CPU1_SA_DQS_DP<9:0>
J 0
(2790 3635);
DISPLAY 0.680851 (2790 3635);
PAINT WHITE (2790 3635);
WIRE 17 -1 (2650 3575)(2650 3625);
WIRE 17 -1 (2650 3525)(2650 3575);
WIRE 17 -1 (2650 3475)(2650 3525);
WIRE 17 -1 (2650 3425)(2650 3475);
WIRE 17 -1 (2650 3375)(2650 3425);
WIRE 17 -1 (2650 3325)(2650 3375);
WIRE 17 -1 (2650 3275)(2650 3325);
WIRE 17 -1 (2650 3225)(2650 3275);
WIRE 17 -1 (2650 3175)(2650 3225);
WIRE 17 -1 (2650 825)(3650 825);
FORCEPROP 2 LAST SIG_NAME M_D_CPU1_SB_CA<6:0>
J 0
(2790 835);
DISPLAY 0.680851 (2790 835);
PAINT WHITE (2790 835);
WIRE 17 -1 (2650 775)(2650 825);
WIRE 17 -1 (2650 725)(2650 775);
WIRE 17 -1 (2650 675)(2650 725);
WIRE 17 -1 (2650 625)(2650 675);
WIRE 17 -1 (2650 575)(2650 625);
WIRE 17 -1 (2650 525)(2650 575);
WIRE 17 -1 (2650 25)(3650 25);
FORCEPROP 2 LAST SIG_NAME M_D_CPU1_SB_CS_N<3:0>
J 0
(2790 35);
DISPLAY 0.680851 (2790 35);
PAINT WHITE (2790 35);
WIRE 17 -1 (2650 -25)(2650 25);
WIRE 17 -1 (2650 -75)(2650 -25);
WIRE 17 -1 (2650 -125)(2650 -75);
WIRE 17 -1 (2650 1925)(3650 1925);
FORCEPROP 2 LAST SIG_NAME M_D_CPU1_SB_DQS_DN<9:0>
J 0
(2790 1935);
DISPLAY 0.680851 (2790 1935);
PAINT WHITE (2790 1935);
WIRE 17 -1 (2650 1875)(2650 1925);
WIRE 17 -1 (2650 1825)(2650 1875);
WIRE 17 -1 (2650 1775)(2650 1825);
WIRE 17 -1 (2650 1725)(2650 1775);
WIRE 17 -1 (2650 1675)(2650 1725);
WIRE 17 -1 (2650 1625)(2650 1675);
WIRE 17 -1 (2650 1575)(2650 1625);
WIRE 17 -1 (2650 1525)(2650 1575);
WIRE 17 -1 (2650 1475)(2650 1525);
WIRE 17 -1 (2650 2475)(3650 2475);
FORCEPROP 2 LAST SIG_NAME M_D_CPU1_SB_DQS_DP<9:0>
J 0
(2790 2485);
DISPLAY 0.680851 (2790 2485);
PAINT WHITE (2790 2485);
WIRE 17 -1 (2650 2425)(2650 2475);
WIRE 17 -1 (2650 2375)(2650 2425);
WIRE 17 -1 (2650 2325)(2650 2375);
WIRE 17 -1 (2650 2275)(2650 2325);
WIRE 17 -1 (2650 2225)(2650 2275);
WIRE 17 -1 (2650 2175)(2650 2225);
WIRE 17 -1 (2650 2125)(2650 2175);
WIRE 17 -1 (2650 2075)(2650 2125);
WIRE 17 -1 (2650 2025)(2650 2075);
WIRE 17 -1 (-875 -325)(-875 -275);
WIRE 17 -1 (-875 -275)(-875 -225);
WIRE 17 -1 (-875 -225)(-875 -175);
WIRE 17 -1 (-875 -175)(-875 -125);
WIRE 17 -1 (-875 -125)(-875 -75);
WIRE 17 -1 (-875 -75)(-875 -25);
WIRE 17 -1 (-875 -25)(-875 25);
WIRE 17 -1 (-1800 25)(-875 25);
FORCEPROP 2 LAST SIG_NAME M_D_CPU1_SB_CB<7:0>
J 0
(-1660 35);
DISPLAY 0.680851 (-1660 35);
PAINT WHITE (-1660 35);
WIRE 17 -1 (-875 75)(-875 125);
WIRE 17 -1 (-875 125)(-875 175);
WIRE 17 -1 (-875 175)(-875 225);
WIRE 17 -1 (-875 225)(-875 275);
WIRE 17 -1 (-875 275)(-875 325);
WIRE 17 -1 (-875 325)(-875 375);
WIRE 17 -1 (-875 375)(-875 425);
WIRE 17 -1 (-875 425)(-875 475);
WIRE 17 -1 (-875 475)(-875 525);
WIRE 17 -1 (-875 525)(-875 575);
WIRE 17 -1 (-875 575)(-875 625);
WIRE 17 -1 (-875 625)(-875 675);
WIRE 17 -1 (-875 675)(-875 725);
WIRE 17 -1 (-875 725)(-875 775);
WIRE 17 -1 (-875 775)(-875 825);
WIRE 17 -1 (-875 825)(-875 875);
WIRE 17 -1 (-875 875)(-875 925);
WIRE 17 -1 (-875 925)(-875 975);
WIRE 17 -1 (-875 975)(-875 1025);
WIRE 17 -1 (-875 1025)(-875 1075);
WIRE 17 -1 (-875 1075)(-875 1125);
WIRE 17 -1 (-875 1125)(-875 1175);
WIRE 17 -1 (-875 1175)(-875 1225);
WIRE 17 -1 (-875 1225)(-875 1275);
WIRE 17 -1 (-875 1275)(-875 1325);
WIRE 17 -1 (-875 1325)(-875 1375);
WIRE 17 -1 (-875 1375)(-875 1425);
WIRE 17 -1 (-875 1425)(-875 1475);
WIRE 17 -1 (-875 1475)(-875 1525);
WIRE 17 -1 (-875 1525)(-875 1575);
WIRE 17 -1 (-875 1575)(-875 1625);
WIRE 17 -1 (-1800 1625)(-875 1625);
FORCEPROP 2 LAST SIG_NAME M_D_CPU1_SB_DQ<31:0>
J 0
(-1660 1635);
DISPLAY 0.680851 (-1660 1635);
PAINT WHITE (-1660 1635);
WIRE 17 -1 (-875 1675)(-875 1725);
WIRE 17 -1 (-875 1725)(-875 1775);
WIRE 17 -1 (-875 1775)(-875 1825);
WIRE 17 -1 (-875 1825)(-875 1875);
WIRE 17 -1 (-875 1875)(-875 1925);
WIRE 17 -1 (-875 1925)(-875 1975);
WIRE 17 -1 (-875 1975)(-875 2025);
WIRE 17 -1 (-1800 2025)(-875 2025);
FORCEPROP 2 LAST SIG_NAME M_D_CPU1_SA_CB<7:0>
J 0
(-1660 2035);
DISPLAY 0.680851 (-1660 2035);
PAINT WHITE (-1660 2035);
WIRE 17 -1 (-875 2075)(-875 2125);
WIRE 17 -1 (-875 2125)(-875 2175);
WIRE 17 -1 (-875 2175)(-875 2225);
WIRE 17 -1 (-875 2225)(-875 2275);
WIRE 17 -1 (-875 2275)(-875 2325);
WIRE 17 -1 (-875 2325)(-875 2375);
WIRE 17 -1 (-875 2375)(-875 2425);
WIRE 17 -1 (-875 2425)(-875 2475);
WIRE 17 -1 (-875 2475)(-875 2525);
WIRE 17 -1 (-875 2525)(-875 2575);
WIRE 17 -1 (-875 2575)(-875 2625);
WIRE 17 -1 (-875 2625)(-875 2675);
WIRE 17 -1 (-875 2675)(-875 2725);
WIRE 17 -1 (-875 2725)(-875 2775);
WIRE 17 -1 (-875 2775)(-875 2825);
WIRE 17 -1 (-875 2825)(-875 2875);
WIRE 17 -1 (-875 2875)(-875 2925);
WIRE 17 -1 (-875 2925)(-875 2975);
WIRE 17 -1 (-875 2975)(-875 3025);
WIRE 17 -1 (-875 3025)(-875 3075);
WIRE 17 -1 (-875 3075)(-875 3125);
WIRE 17 -1 (-875 3125)(-875 3175);
WIRE 17 -1 (-875 3175)(-875 3225);
WIRE 17 -1 (-875 3225)(-875 3275);
WIRE 17 -1 (-875 3275)(-875 3325);
WIRE 17 -1 (-875 3325)(-875 3375);
WIRE 17 -1 (-875 3375)(-875 3425);
WIRE 17 -1 (-875 3425)(-875 3475);
WIRE 17 -1 (-875 3475)(-875 3525);
WIRE 17 -1 (-875 3525)(-875 3575);
WIRE 17 -1 (-875 3575)(-875 3625);
WIRE 17 -1 (-1800 3625)(-875 3625);
FORCEPROP 2 LAST SIG_NAME M_D_CPU1_SA_DQ<31:0>
J 0
(-1660 3635);
DISPLAY 0.680851 (-1660 3635);
PAINT WHITE (-1660 3635);
WIRE 17 -1 (-875 -475)(-875 -425);
WIRE 17 -1 (-1800 -425)(-875 -425);
FORCEPROP 2 LAST SIG_NAME M_D_CPU1_CLK_DP<1:0>
J 0
(-1660 -415);
DISPLAY 0.680851 (-1660 -415);
PAINT WHITE (-1660 -415);
WIRE 17 -1 (-875 -575)(-875 -525);
WIRE 17 -1 (-1800 -525)(-875 -525);
FORCEPROP 2 LAST SIG_NAME M_D_CPU1_CLK_DN<1:0>
J 0
(-1660 -515);
DISPLAY 0.680851 (-1660 -515);
PAINT WHITE (-1660 -515);
WIRE 16 -1 (-775 2450)(-325 2450);
WIRE 16 -1 (-775 -550)(-325 -550);
WIRE 16 -1 (-775 -600)(-325 -600);
WIRE 16 -1 (-775 -450)(-325 -450);
WIRE 16 -1 (-775 -500)(-325 -500);
WIRE 16 -1 (-775 3600)(-325 3600);
WIRE 16 -1 (-775 3550)(-325 3550);
WIRE 16 -1 (-775 3500)(-325 3500);
WIRE 16 -1 (-775 3450)(-325 3450);
WIRE 16 -1 (-775 3400)(-325 3400);
WIRE 16 -1 (-775 3350)(-325 3350);
WIRE 16 -1 (-775 3300)(-325 3300);
WIRE 16 -1 (-775 3250)(-325 3250);
WIRE 16 -1 (-775 3200)(-325 3200);
WIRE 16 -1 (-775 3150)(-325 3150);
WIRE 16 -1 (-775 3100)(-325 3100);
WIRE 16 -1 (-775 3050)(-325 3050);
WIRE 16 -1 (-775 3000)(-325 3000);
WIRE 16 -1 (-775 2950)(-325 2950);
WIRE 16 -1 (-775 2900)(-325 2900);
WIRE 16 -1 (-775 2850)(-325 2850);
WIRE 16 -1 (-775 2800)(-325 2800);
WIRE 16 -1 (-775 2750)(-325 2750);
WIRE 16 -1 (-775 2700)(-325 2700);
WIRE 16 -1 (-775 2650)(-325 2650);
WIRE 16 -1 (-775 2600)(-325 2600);
WIRE 16 -1 (-775 2550)(-325 2550);
WIRE 16 -1 (-775 2500)(-325 2500);
WIRE 16 -1 (-775 2400)(-325 2400);
WIRE 16 -1 (-775 2350)(-325 2350);
WIRE 16 -1 (-775 2300)(-325 2300);
WIRE 16 -1 (-775 2250)(-325 2250);
WIRE 16 -1 (-775 2200)(-325 2200);
WIRE 16 -1 (-775 2150)(-325 2150);
WIRE 16 -1 (-775 2100)(-325 2100);
WIRE 16 -1 (-775 2050)(-325 2050);
WIRE 16 -1 (-775 2000)(-325 2000);
WIRE 16 -1 (-775 1950)(-325 1950);
WIRE 16 -1 (-775 1900)(-325 1900);
WIRE 16 -1 (-775 1850)(-325 1850);
WIRE 16 -1 (-775 1800)(-325 1800);
WIRE 16 -1 (-775 1750)(-325 1750);
WIRE 16 -1 (-775 1700)(-325 1700);
WIRE 16 -1 (-775 1650)(-325 1650);
WIRE 16 -1 (-775 1600)(-325 1600);
WIRE 16 -1 (-775 1550)(-325 1550);
WIRE 16 -1 (-775 1500)(-325 1500);
WIRE 16 -1 (-775 1450)(-325 1450);
WIRE 16 -1 (-775 1400)(-325 1400);
WIRE 16 -1 (-775 1350)(-325 1350);
WIRE 16 -1 (-775 1300)(-325 1300);
WIRE 16 -1 (-775 1250)(-325 1250);
WIRE 16 -1 (-775 1200)(-325 1200);
WIRE 16 -1 (-775 1150)(-325 1150);
WIRE 16 -1 (-775 1100)(-325 1100);
WIRE 16 -1 (-775 1050)(-325 1050);
WIRE 16 -1 (-775 1000)(-325 1000);
WIRE 16 -1 (-775 950)(-325 950);
WIRE 16 -1 (-775 900)(-325 900);
WIRE 16 -1 (-775 850)(-325 850);
WIRE 16 -1 (-775 800)(-325 800);
WIRE 16 -1 (-775 750)(-325 750);
WIRE 16 -1 (-775 700)(-325 700);
WIRE 16 -1 (-775 650)(-325 650);
WIRE 16 -1 (-775 600)(-325 600);
WIRE 16 -1 (-775 550)(-325 550);
WIRE 16 -1 (-775 500)(-325 500);
WIRE 16 -1 (-775 450)(-325 450);
WIRE 16 -1 (-775 400)(-325 400);
WIRE 16 -1 (-775 350)(-325 350);
WIRE 16 -1 (-775 300)(-325 300);
WIRE 16 -1 (-775 250)(-325 250);
WIRE 16 -1 (-775 200)(-325 200);
WIRE 16 -1 (-775 150)(-325 150);
WIRE 16 -1 (-775 100)(-325 100);
WIRE 16 -1 (-775 50)(-325 50);
WIRE 16 -1 (-775 0)(-325 0);
WIRE 16 -1 (-775 -50)(-325 -50);
WIRE 16 -1 (-775 -100)(-325 -100);
WIRE 16 -1 (-775 -150)(-325 -150);
WIRE 16 -1 (-775 -200)(-325 -200);
WIRE 16 -1 (-775 -250)(-325 -250);
WIRE 16 -1 (-775 -300)(-325 -300);
WIRE 16 -1 (-775 -350)(-325 -350);
WIRE 16 -1 (3650 450)(2125 450);
FORCEPROP 2 LAST SIG_NAME M_D_CPU1_SB_PAR
J 0
(2759 459);
DISPLAY 0.680851 (2759 459);
PAINT WHITE (2759 459);
WIRE 16 -1 (2125 2000)(2550 2000);
WIRE 16 -1 (2125 2050)(2550 2050);
WIRE 16 -1 (2125 2100)(2550 2100);
WIRE 16 -1 (2125 2150)(2550 2150);
WIRE 16 -1 (2125 2200)(2550 2200);
WIRE 16 -1 (2125 2250)(2550 2250);
WIRE 16 -1 (2125 2300)(2550 2300);
WIRE 16 -1 (2125 2350)(2550 2350);
WIRE 16 -1 (2125 2400)(2550 2400);
WIRE 16 -1 (2125 2450)(2550 2450);
WIRE 16 -1 (2125 1450)(2550 1450);
WIRE 16 -1 (2125 1500)(2550 1500);
WIRE 16 -1 (2125 1550)(2550 1550);
WIRE 16 -1 (2125 1600)(2550 1600);
WIRE 16 -1 (2125 1650)(2550 1650);
WIRE 16 -1 (2125 1700)(2550 1700);
WIRE 16 -1 (2125 1750)(2550 1750);
WIRE 16 -1 (2125 1800)(2550 1800);
WIRE 16 -1 (2125 1850)(2550 1850);
WIRE 16 -1 (2125 1900)(2550 1900);
WIRE 16 -1 (2125 -150)(2550 -150);
WIRE 16 -1 (2125 -100)(2550 -100);
WIRE 16 -1 (2125 -50)(2550 -50);
WIRE 16 -1 (2125 0)(2550 0);
WIRE 16 -1 (2125 500)(2550 500);
WIRE 16 -1 (2125 550)(2550 550);
WIRE 16 -1 (2125 600)(2550 600);
WIRE 16 -1 (2125 650)(2550 650);
WIRE 16 -1 (2125 700)(2550 700);
WIRE 16 -1 (2125 750)(2550 750);
WIRE 16 -1 (2125 800)(2550 800);
WIRE 16 -1 (3650 950)(2125 950);
FORCEPROP 2 LAST SIG_NAME M_D_CPU1_SA_PAR
J 0
(2759 959);
DISPLAY 0.680851 (2759 959);
PAINT WHITE (2759 959);
WIRE 16 -1 (2125 3150)(2550 3150);
WIRE 16 -1 (2125 3200)(2550 3200);
WIRE 16 -1 (2125 3250)(2550 3250);
WIRE 16 -1 (2125 3300)(2550 3300);
WIRE 16 -1 (2125 3350)(2550 3350);
WIRE 16 -1 (2125 3400)(2550 3400);
WIRE 16 -1 (2125 3450)(2550 3450);
WIRE 16 -1 (2125 3500)(2550 3500);
WIRE 16 -1 (2125 3550)(2550 3550);
WIRE 16 -1 (2125 3600)(2550 3600);
WIRE 16 -1 (2125 2600)(2550 2600);
WIRE 16 -1 (2125 2650)(2550 2650);
WIRE 16 -1 (2125 2700)(2550 2700);
WIRE 16 -1 (2125 2750)(2550 2750);
WIRE 16 -1 (2125 2800)(2550 2800);
WIRE 16 -1 (2125 2850)(2550 2850);
WIRE 16 -1 (2125 2900)(2550 2900);
WIRE 16 -1 (2125 2950)(2550 2950);
WIRE 16 -1 (2125 3000)(2550 3000);
WIRE 16 -1 (2125 3050)(2550 3050);
WIRE 16 -1 (2125 150)(2550 150);
WIRE 16 -1 (2125 200)(2550 200);
WIRE 16 -1 (2125 250)(2550 250);
WIRE 16 -1 (2125 300)(2550 300);
WIRE 16 -1 (2125 1000)(2550 1000);
WIRE 16 -1 (2125 1050)(2550 1050);
WIRE 16 -1 (2125 1100)(2550 1100);
WIRE 16 -1 (2125 1150)(2550 1150);
WIRE 16 -1 (2125 1200)(2550 1200);
WIRE 16 -1 (2125 1250)(2550 1250);
WIRE 16 -1 (2125 1300)(2550 1300);
WIRE 16 -1 (3650 -500)(2125 -500);
FORCEPROP 2 LAST SIG_NAME M_D_CPU1_SB_RSP<0>
J 0
(2759 -491);
DISPLAY 0.680851 (2759 -491);
PAINT WHITE (2759 -491);
WIRE 16 -1 (3650 -450)(2125 -450);
FORCEPROP 2 LAST SIG_NAME M_D_CPU1_SB_RSP<1>
J 0
(2759 -441);
DISPLAY 0.680851 (2759 -441);
PAINT WHITE (2759 -441);
WIRE 16 -1 (3650 -350)(2125 -350);
FORCEPROP 2 LAST SIG_NAME M_D_CPU1_SA_RSP<0>
J 0
(2759 -341);
DISPLAY 0.680851 (2759 -341);
PAINT WHITE (2759 -341);
WIRE 16 -1 (3650 -300)(2125 -300);
FORCEPROP 2 LAST SIG_NAME M_D_CPU1_SA_RSP<1>
J 0
(2759 -291);
DISPLAY 0.680851 (2759 -291);
PAINT WHITE (2759 -291);
WIRE 16 -1 (3650 -600)(2125 -600);
FORCEPROP 2 LAST SIG_NAME M_D_CPU1_ALERT_N
J 0
(2759 -591);
DISPLAY 0.680851 (2759 -591);
PAINT WHITE (2759 -591);
QUIT
